FILE_TYPE = MACRO_DRAWING;
SET COLOR_WIRE YELLOW;
SET COLOR_PROP MONO;
SET COLOR_DOT WHITE;
SET COLOR_ARC YELLOW;
SET COLOR_BODY GREEN;
SET COLOR_NOTE MONO;
SET PROP_DISPLAY VALUE;
SET PAGE_NUMBER P201;
FORCEADD OFFPAGE..2
(-500 3325);
FORCEPROP 2 LAST $XR0 112 
J 0
(-311 3325);
DISPLAY 0.638298 (-311 3325);
PAINT MONO (-311 3325);
FORCEPROP 2 LAST $XR1 190 
J 0
(-311 3289);
DISPLAY 0.638298 (-311 3289);
PAINT MONO (-311 3289);
FORCEPROP 1 LAST COMMENT_BODY TRUE
J 0
(-545 3230);
DISPLAY 1.170213 (-545 3230);
PAINT GREEN (-545 3230);
DISPLAY INVISIBLE (-545 3230);
FORCEPROP 1 LAST OFFPAGE TRUE
J 0
(-175 3200);
DISPLAY 1.170213 (-175 3200);
PAINT GREEN (-175 3200);
DISPLAY INVISIBLE (-175 3200);
FORCEPROP 2 LAST ROOM PVCCIN_CPU0_VR
J 0
(-925 3400);
DISPLAY 1.361702 (-925 3400);
PAINT ORANGE (-925 3400);
DISPLAY INVISIBLE (-925 3400);
FORCEPROP 2 LAST CDS_LIB mstr_standard
J 0
(-500 3325);
PAINT ORANGE (-500 3325);
DISPLAY INVISIBLE (-500 3325);
FORCEPROP 2 LAST PATH I1
J 0
(-325 3400);
DISPLAY 1.021277 (-325 3400);
PAINT ORANGE (-325 3400);
DISPLAY INVISIBLE (-325 3400);
FORCEADD OFFPAGE..2
(-1050 2425);
FORCEPROP 2 LAST $XR0 202 
J 0
(-861 2425);
DISPLAY 0.638298 (-861 2425);
PAINT MONO (-861 2425);
FORCEPROP 1 LAST COMMENT_BODY TRUE
J 0
(-1095 2330);
DISPLAY 1.170213 (-1095 2330);
PAINT GREEN (-1095 2330);
DISPLAY INVISIBLE (-1095 2330);
FORCEPROP 1 LAST OFFPAGE TRUE
J 0
(-725 2300);
DISPLAY 1.170213 (-725 2300);
PAINT GREEN (-725 2300);
DISPLAY INVISIBLE (-725 2300);
FORCEPROP 2 LAST ROOM PVCCIN_CPU0_VR
J 0
(-1475 2500);
DISPLAY 1.361702 (-1475 2500);
PAINT ORANGE (-1475 2500);
DISPLAY INVISIBLE (-1475 2500);
FORCEPROP 2 LAST CDS_LIB mstr_standard
J 0
(-1050 2425);
PAINT ORANGE (-1050 2425);
DISPLAY INVISIBLE (-1050 2425);
FORCEPROP 2 LAST PATH I10
J 0
(-875 2500);
DISPLAY 1.021277 (-875 2500);
PAINT ORANGE (-875 2500);
DISPLAY INVISIBLE (-875 2500);
FORCEADD RES..2
(-1100 2000);
FORCEPROP 1 LAST WATTAGE 1/16W
J 0
(-1060 1975);
DISPLAY 0.617021 (-1060 1975);
PAINT SKYBLUE (-1060 1975);
FORCEPROP 1 LAST PACK_TYPE 0402
J 0
(-1060 1825);
DISPLAY 0.617021 (-1060 1825);
PAINT SKYBLUE (-1060 1825);
FORCEPROP 1 LAST PART_NUMBER G21796-001
J 0
(-1060 1875);
DISPLAY 0.617021 (-1060 1875);
PAINT BLUE (-1060 1875);
FORCEPROP 1 LAST MATERIAL EMPTY
J 0
(-1060 1925);
DISPLAY 0.617021 (-1060 1925);
PAINT RED (-1060 1925);
FORCEPROP 1 LAST TOLERANCE 1%
J 0
(-1055 2025);
DISPLAY 0.617021 (-1055 2025);
PAINT SKYBLUE (-1055 2025);
FORCEPROP 1 LAST VALUE 2.0K
J 0
(-1055 2075);
DISPLAY 0.617021 (-1055 2075);
PAINT SKYBLUE (-1055 2075);
FORCEPROP 1 LAST LOCATION R6P32
J 0
(-1055 2125);
DISPLAY 0.617021 (-1055 2125);
PAINT AQUA (-1055 2125);
FORCEPROP 1 LASTPIN (-1100 1900) $PN 2
J 0
(-1095 1910);
DISPLAY 0.787234 (-1095 1910);
PAINT ORANGE (-1095 1910);
DISPLAY INVISIBLE (-1095 1910);
FORCEPROP 2 LAST CDS_LIB mstr_discrete
J 0
(-1100 2000);
PAINT ORANGE (-1100 2000);
DISPLAY INVISIBLE (-1100 2000);
FORCEPROP 2 LAST ROOM PVCCIN_CPU0_VR
J 0
(-1250 2150);
DISPLAY 1.361702 (-1250 2150);
PAINT ORANGE (-1250 2150);
DISPLAY INVISIBLE (-1250 2150);
FORCEPROP 1 LASTPIN (-1100 2100) $PN 1
J 0
(-1095 2062);
DISPLAY 0.787234 (-1095 2062);
PAINT ORANGE (-1095 2062);
DISPLAY INVISIBLE (-1095 2062);
FORCEPROP 2 LAST CDS_LOCATION R6P32
J 0
(-1055 2125);
DISPLAY 0.617021 (-1055 2125);
PAINT AQUA (-1055 2125);
DISPLAY INVISIBLE (-1055 2125);
FORCEPROP 1 LAST PATH I102
J 0
(-1050 2175);
DISPLAY 0.978723 (-1050 2175);
PAINT WHITE (-1050 2175);
DISPLAY INVISIBLE (-1050 2175);
FORCEPROP 2 LAST $SEC 1
J 0
(-1050 2225);
PAINT MONO (-1050 2225);
DISPLAY INVISIBLE (-1050 2225);
FORCEPROP 2 LAST CDS_SEC 1
J 0
(-1050 2225);
PAINT MONO (-1050 2225);
DISPLAY INVISIBLE (-1050 2225);
FORCEADD RES..2
(-850 2000);
FORCEPROP 1 LAST WATTAGE 1/16W
J 0
(-810 1975);
DISPLAY 0.617021 (-810 1975);
PAINT SKYBLUE (-810 1975);
FORCEPROP 1 LAST PACK_TYPE 0402
J 0
(-810 1825);
DISPLAY 0.617021 (-810 1825);
PAINT SKYBLUE (-810 1825);
FORCEPROP 1 LAST PART_NUMBER G21796-001
J 0
(-810 1875);
DISPLAY 0.617021 (-810 1875);
PAINT BLUE (-810 1875);
FORCEPROP 1 LAST MATERIAL EMPTY
J 0
(-810 1925);
DISPLAY 0.617021 (-810 1925);
PAINT RED (-810 1925);
FORCEPROP 1 LAST TOLERANCE 1%
J 0
(-805 2025);
DISPLAY 0.617021 (-805 2025);
PAINT SKYBLUE (-805 2025);
FORCEPROP 1 LAST VALUE 2.0K
J 0
(-805 2075);
DISPLAY 0.617021 (-805 2075);
PAINT SKYBLUE (-805 2075);
FORCEPROP 1 LAST LOCATION R6P37
J 0
(-805 2125);
DISPLAY 0.617021 (-805 2125);
PAINT AQUA (-805 2125);
FORCEPROP 1 LASTPIN (-850 1900) $PN 2
J 0
(-845 1910);
DISPLAY 0.787234 (-845 1910);
PAINT ORANGE (-845 1910);
DISPLAY INVISIBLE (-845 1910);
FORCEPROP 2 LAST CDS_LIB mstr_discrete
J 0
(-850 2000);
PAINT ORANGE (-850 2000);
DISPLAY INVISIBLE (-850 2000);
FORCEPROP 2 LAST ROOM PVCCIN_CPU0_VR
J 0
(-1000 2150);
DISPLAY 1.361702 (-1000 2150);
PAINT ORANGE (-1000 2150);
DISPLAY INVISIBLE (-1000 2150);
FORCEPROP 1 LASTPIN (-850 2100) $PN 1
J 0
(-845 2062);
DISPLAY 0.787234 (-845 2062);
PAINT ORANGE (-845 2062);
DISPLAY INVISIBLE (-845 2062);
FORCEPROP 2 LAST CDS_LOCATION R6P37
J 0
(-805 2125);
DISPLAY 0.617021 (-805 2125);
PAINT AQUA (-805 2125);
DISPLAY INVISIBLE (-805 2125);
FORCEPROP 1 LAST PATH I103
J 0
(-800 2175);
DISPLAY 0.978723 (-800 2175);
PAINT WHITE (-800 2175);
DISPLAY INVISIBLE (-800 2175);
FORCEPROP 2 LAST $SEC 1
J 0
(-800 2225);
PAINT MONO (-800 2225);
DISPLAY INVISIBLE (-800 2225);
FORCEPROP 2 LAST CDS_SEC 1
J 0
(-800 2225);
PAINT MONO (-800 2225);
DISPLAY INVISIBLE (-800 2225);
FORCEADD RES..1
(-6675 2525);
FORCEPROP 1 LAST WATTAGE 1/16W
J 2
(-6700 2375);
DISPLAY 0.617021 (-6700 2375);
PAINT SKYBLUE (-6700 2375);
FORCEPROP 1 LAST PACK_TYPE 0402
J 0
(-6900 2475);
DISPLAY 0.617021 (-6900 2475);
PAINT SKYBLUE (-6900 2475);
FORCEPROP 1 LAST VALUE 10.0
J 2
(-6700 2425);
DISPLAY 0.617021 (-6700 2425);
PAINT SKYBLUE (-6700 2425);
FORCEPROP 1 LASTPIN (-6775 2525) $PN 1
J 0
(-6763 2537);
DISPLAY 0.617021 (-6763 2537);
PAINT ORANGE (-6763 2537);
FORCEPROP 2 LAST NO_XNET_CONNECTION 1
J 0
(-6725 2725);
PAINT MONO (-6725 2725);
FORCEPROP 1 LAST MATERIAL CHIP
J 0
(-6675 2375);
DISPLAY 0.617021 (-6675 2375);
PAINT SKYBLUE (-6675 2375);
FORCEPROP 1 LAST TOLERANCE 1%
J 0
(-6675 2425);
DISPLAY 0.617021 (-6675 2425);
PAINT SKYBLUE (-6675 2425);
FORCEPROP 1 LAST PART_NUMBER G21796-066
J 0
(-6725 2625);
DISPLAY 0.617021 (-6725 2625);
PAINT BLUE (-6725 2625);
FORCEPROP 1 LAST LOCATION R4E8
J 0
(-6725 2575);
DISPLAY 0.617021 (-6725 2575);
PAINT AQUA (-6725 2575);
FORCEPROP 1 LASTPIN (-6575 2525) $PN 2
J 0
(-6613 2537);
DISPLAY 0.617021 (-6613 2537);
PAINT ORANGE (-6613 2537);
FORCEPROP 2 LAST CDS_LIB mstr_discrete
J 0
(-6675 2525);
PAINT MONO (-6675 2525);
DISPLAY INVISIBLE (-6675 2525);
FORCEPROP 2 LAST ROOM PVCCIN_CPU0_VR
J 0
(-6725 2675);
DISPLAY 1.021277 (-6725 2675);
PAINT ORANGE (-6725 2675);
DISPLAY INVISIBLE (-6725 2675);
FORCEPROP 1 LAST PATH I109
J 0
(-6725 2675);
DISPLAY 0.978723 (-6725 2675);
PAINT WHITE (-6725 2675);
DISPLAY INVISIBLE (-6725 2675);
FORCEPROP 2 LAST CDS_LOCATION R4E8
J 0
(-6725 2575);
DISPLAY 0.617021 (-6725 2575);
PAINT AQUA (-6725 2575);
DISPLAY INVISIBLE (-6725 2575);
FORCEPROP 2 LAST SEC 1
J 0
(-6725 2725);
DISPLAY 0.680851 (-6725 2725);
PAINT MONO (-6725 2725);
DISPLAY INVISIBLE (-6725 2725);
FORCEPROP 2 LAST SEC_TYPE 0402
J 0
(-6725 2725);
DISPLAY 1.021277 (-6725 2725);
PAINT ORANGE (-6725 2725);
DISPLAY INVISIBLE (-6725 2725);
FORCEADD OFFPAGE..2
(-1050 2325);
FORCEPROP 2 LAST $XR0 203 
J 0
(-861 2325);
DISPLAY 0.638298 (-861 2325);
PAINT MONO (-861 2325);
FORCEPROP 1 LAST COMMENT_BODY TRUE
J 0
(-1095 2230);
DISPLAY 1.170213 (-1095 2230);
PAINT GREEN (-1095 2230);
DISPLAY INVISIBLE (-1095 2230);
FORCEPROP 1 LAST OFFPAGE TRUE
J 0
(-725 2200);
DISPLAY 1.170213 (-725 2200);
PAINT GREEN (-725 2200);
DISPLAY INVISIBLE (-725 2200);
FORCEPROP 2 LAST ROOM PVCCIN_CPU0_VR
J 0
(-1475 2400);
DISPLAY 1.361702 (-1475 2400);
PAINT ORANGE (-1475 2400);
DISPLAY INVISIBLE (-1475 2400);
FORCEPROP 2 LAST CDS_LIB mstr_standard
J 0
(-1050 2325);
PAINT ORANGE (-1050 2325);
DISPLAY INVISIBLE (-1050 2325);
FORCEPROP 2 LAST PATH I11
J 0
(-875 2400);
DISPLAY 1.021277 (-875 2400);
PAINT ORANGE (-875 2400);
DISPLAY INVISIBLE (-875 2400);
FORCEADD RES..1
(-6250 2075);
FORCEPROP 1 LAST WATTAGE 1/16W
J 2
(-6275 1925);
DISPLAY 0.617021 (-6275 1925);
PAINT SKYBLUE (-6275 1925);
FORCEPROP 1 LAST TOLERANCE 1%
J 0
(-6250 1975);
DISPLAY 0.617021 (-6250 1975);
PAINT SKYBLUE (-6250 1975);
FORCEPROP 1 LAST VALUE 10.0
J 2
(-6275 1975);
DISPLAY 0.617021 (-6275 1975);
PAINT SKYBLUE (-6275 1975);
FORCEPROP 1 LAST PACK_TYPE 0402
J 0
(-6350 2025);
DISPLAY 0.617021 (-6350 2025);
PAINT SKYBLUE (-6350 2025);
FORCEPROP 1 LASTPIN (-6350 2075) $PN 1
J 0
(-6338 2087);
DISPLAY 0.617021 (-6338 2087);
PAINT ORANGE (-6338 2087);
FORCEPROP 1 LAST LOCATION R4D39
J 0
(-6300 2125);
DISPLAY 0.617021 (-6300 2125);
PAINT AQUA (-6300 2125);
FORCEPROP 1 LASTPIN (-6150 2075) $PN 2
J 0
(-6188 2087);
DISPLAY 0.617021 (-6188 2087);
PAINT ORANGE (-6188 2087);
FORCEPROP 2 LAST NO_XNET_CONNECTION 1
J 0
(-6300 2275);
PAINT MONO (-6300 2275);
FORCEPROP 1 LAST MATERIAL CHIP
J 0
(-6250 1925);
DISPLAY 0.617021 (-6250 1925);
PAINT SKYBLUE (-6250 1925);
FORCEPROP 1 LAST PART_NUMBER G21796-066
J 0
(-6300 2175);
DISPLAY 0.617021 (-6300 2175);
PAINT BLUE (-6300 2175);
FORCEPROP 2 LAST CDS_LOCATION R4D39
J 0
(-6300 2125);
DISPLAY 0.617021 (-6300 2125);
PAINT AQUA (-6300 2125);
DISPLAY INVISIBLE (-6300 2125);
FORCEPROP 2 LAST SEC 1
J 0
(-6300 2275);
DISPLAY 0.680851 (-6300 2275);
PAINT MONO (-6300 2275);
DISPLAY INVISIBLE (-6300 2275);
FORCEPROP 2 LAST ROOM PVCCIN_CPU0_VR
J 0
(-6300 2225);
DISPLAY 1.021277 (-6300 2225);
PAINT ORANGE (-6300 2225);
DISPLAY INVISIBLE (-6300 2225);
FORCEPROP 1 LAST PATH I110
J 0
(-6300 2225);
DISPLAY 0.978723 (-6300 2225);
PAINT WHITE (-6300 2225);
DISPLAY INVISIBLE (-6300 2225);
FORCEPROP 2 LAST CDS_LIB mstr_discrete
J 0
(-6250 2075);
PAINT MONO (-6250 2075);
DISPLAY INVISIBLE (-6250 2075);
FORCEPROP 2 LAST SEC_TYPE 0402
J 0
(-6300 2275);
DISPLAY 1.021277 (-6300 2275);
PAINT ORANGE (-6300 2275);
DISPLAY INVISIBLE (-6300 2275);
FORCEADD RES..2
R 2
(-3050 4125);
FORCEPROP 1 LAST PART_NUMBER G21796-026
J 2
(-3090 4000);
DISPLAY 0.617021 (-3090 4000);
PAINT BLUE (-3090 4000);
FORCEPROP 1 LAST MATERIAL CHIP
J 2
(-3090 4050);
DISPLAY 0.617021 (-3090 4050);
PAINT SKYBLUE (-3090 4050);
FORCEPROP 1 LAST PACK_TYPE 0402
J 2
(-3090 3950);
DISPLAY 0.617021 (-3090 3950);
PAINT SKYBLUE (-3090 3950);
FORCEPROP 1 LASTPIN (-3050 4025) $PN 2
J 2
(-3055 4035);
DISPLAY 0.617021 (-3055 4035);
PAINT ORANGE (-3055 4035);
FORCEPROP 1 LAST WATTAGE 1/16W
J 2
(-3090 4100);
DISPLAY 0.617021 (-3090 4100);
PAINT SKYBLUE (-3090 4100);
FORCEPROP 1 LAST TOLERANCE 1%
J 2
(-3095 4150);
DISPLAY 0.617021 (-3095 4150);
PAINT SKYBLUE (-3095 4150);
FORCEPROP 1 LAST VALUE 1.00K
J 2
(-3095 4200);
DISPLAY 0.617021 (-3095 4200);
PAINT SKYBLUE (-3095 4200);
FORCEPROP 1 LAST LOCATION R4E3
J 2
(-3095 4250);
DISPLAY 0.617021 (-3095 4250);
PAINT AQUA (-3095 4250);
FORCEPROP 1 LASTPIN (-3050 4225) $PN 1
J 2
(-3055 4187);
DISPLAY 0.617021 (-3055 4187);
PAINT ORANGE (-3055 4187);
FORCEPROP 2 LAST ROOM PVCCIN_CPU0_VR
J 2
(-3100 4300);
DISPLAY 1.361702 (-3100 4300);
PAINT ORANGE (-3100 4300);
DISPLAY INVISIBLE (-3100 4300);
FORCEPROP 1 LAST PATH I111
J 2
(-3100 4300);
DISPLAY 0.978723 (-3100 4300);
PAINT WHITE (-3100 4300);
DISPLAY INVISIBLE (-3100 4300);
FORCEPROP 2 LAST CDS_LOCATION R4E3
J 2
(-3095 4250);
DISPLAY 0.617021 (-3095 4250);
PAINT AQUA (-3095 4250);
DISPLAY INVISIBLE (-3095 4250);
FORCEPROP 2 LAST SEC 1
J 2
(-3100 4350);
DISPLAY 0.680851 (-3100 4350);
PAINT MONO (-3100 4350);
DISPLAY INVISIBLE (-3100 4350);
FORCEPROP 2 LAST SEC_TYPE 0402
J 2
(-3100 4350);
DISPLAY 1.021277 (-3100 4350);
PAINT ORANGE (-3100 4350);
DISPLAY INVISIBLE (-3100 4350);
FORCEPROP 2 LAST CDS_LIB mstr_discrete
J 0
(-3050 4125);
PAINT ORANGE (-3050 4125);
DISPLAY INVISIBLE (-3050 4125);
FORCEADD P3V3_STBY..1
(-4250 4600);
FORCEPROP 3 LASTPIN (-4250 4550) SIG_NAME P3V3_STBY\g
J 0
(-4240 4560);
DISPLAY 0.659574 (-4240 4560);
PAINT MONO (-4240 4560);
DISPLAY INVISIBLE (-4240 4560);
FORCEPROP 1 LAST HDL_POWER P3V3_STBY
J 0
(-4550 4475);
DISPLAY 0.872340 (-4550 4475);
PAINT ORANGE (-4550 4475);
DISPLAY INVISIBLE (-4550 4475);
FORCEPROP 1 LAST BODY_TYPE PLUMBING
J 0
(-4295 4557);
DISPLAY 0.340426 (-4295 4557);
PAINT GREEN (-4295 4557);
DISPLAY INVISIBLE (-4295 4557);
FORCEPROP 1 LAST VOLTAGE 3.3V
J 0
(-4295 4557);
DISPLAY 0.340426 (-4295 4557);
PAINT SKYBLUE (-4295 4557);
DISPLAY INVISIBLE (-4295 4557);
FORCEPROP 1 LAST PATH I112
J 0
(-4205 4602);
DISPLAY 0.340426 (-4205 4602);
PAINT GREEN (-4205 4602);
DISPLAY INVISIBLE (-4205 4602);
FORCEPROP 2 LAST CDS_LIB mstr_symbols
J 0
(-4250 4600);
PAINT ORANGE (-4250 4600);
DISPLAY INVISIBLE (-4250 4600);
FORCEPROP 1 LAST SIZE 1B
J 0
(-4205 4622);
DISPLAY 0.340426 (-4205 4622);
PAINT GREEN (-4205 4622);
DISPLAY INVISIBLE (-4205 4622);
FORCEADD P3V3_STBY..1
(-3050 4550);
FORCEPROP 3 LASTPIN (-3050 4500) SIG_NAME P3V3_STBY\g
J 0
(-3040 4510);
DISPLAY 0.659574 (-3040 4510);
PAINT MONO (-3040 4510);
DISPLAY INVISIBLE (-3040 4510);
FORCEPROP 1 LAST HDL_POWER P3V3_STBY
J 0
(-3350 4425);
DISPLAY 0.872340 (-3350 4425);
PAINT ORANGE (-3350 4425);
DISPLAY INVISIBLE (-3350 4425);
FORCEPROP 1 LAST BODY_TYPE PLUMBING
J 0
(-3095 4507);
DISPLAY 0.340426 (-3095 4507);
PAINT GREEN (-3095 4507);
DISPLAY INVISIBLE (-3095 4507);
FORCEPROP 1 LAST VOLTAGE 3.3V
J 0
(-3095 4507);
DISPLAY 0.340426 (-3095 4507);
PAINT SKYBLUE (-3095 4507);
DISPLAY INVISIBLE (-3095 4507);
FORCEPROP 1 LAST PATH I113
J 0
(-3005 4552);
DISPLAY 0.340426 (-3005 4552);
PAINT GREEN (-3005 4552);
DISPLAY INVISIBLE (-3005 4552);
FORCEPROP 2 LAST CDS_LIB mstr_symbols
J 0
(-3050 4550);
PAINT ORANGE (-3050 4550);
DISPLAY INVISIBLE (-3050 4550);
FORCEPROP 1 LAST SIZE 1B
J 0
(-3005 4572);
DISPLAY 0.340426 (-3005 4572);
PAINT GREEN (-3005 4572);
DISPLAY INVISIBLE (-3005 4572);
FORCEADD P3V3_STBY..1
(-375 2325);
FORCEPROP 3 LASTPIN (-375 2275) SIG_NAME P3V3_STBY\g
J 0
(-365 2285);
DISPLAY 0.659574 (-365 2285);
PAINT MONO (-365 2285);
DISPLAY INVISIBLE (-365 2285);
FORCEPROP 1 LAST HDL_POWER P3V3_STBY
J 0
(-675 2200);
DISPLAY 0.872340 (-675 2200);
PAINT ORANGE (-675 2200);
DISPLAY INVISIBLE (-675 2200);
FORCEPROP 1 LAST BODY_TYPE PLUMBING
J 0
(-420 2282);
DISPLAY 0.340426 (-420 2282);
PAINT GREEN (-420 2282);
DISPLAY INVISIBLE (-420 2282);
FORCEPROP 1 LAST PATH I115
J 0
(-330 2327);
DISPLAY 0.340426 (-330 2327);
PAINT GREEN (-330 2327);
DISPLAY INVISIBLE (-330 2327);
FORCEPROP 1 LAST SIZE 1B
J 0
(-330 2347);
DISPLAY 0.340426 (-330 2347);
PAINT GREEN (-330 2347);
DISPLAY INVISIBLE (-330 2347);
FORCEPROP 2 LAST CDS_LIB mstr_symbols
J 0
(-375 2325);
PAINT ORANGE (-375 2325);
DISPLAY INVISIBLE (-375 2325);
FORCEPROP 1 LAST VOLTAGE 3.3V
J 0
(-420 2282);
DISPLAY 0.340426 (-420 2282);
PAINT SKYBLUE (-420 2282);
DISPLAY INVISIBLE (-420 2282);
FORCEADD RES..2
(-1575 4200);
FORCEPROP 1 LAST PACK_TYPE 0402
J 0
(-1535 4025);
DISPLAY 0.617021 (-1535 4025);
PAINT SKYBLUE (-1535 4025);
FORCEPROP 1 LAST PART_NUMBER G21796-311
J 0
(-1535 4075);
DISPLAY 0.617021 (-1535 4075);
PAINT BLUE (-1535 4075);
FORCEPROP 1 LASTPIN (-1575 4100) $PN 2
J 0
(-1570 4110);
DISPLAY 0.617021 (-1570 4110);
PAINT ORANGE (-1570 4110);
FORCEPROP 1 LASTPIN (-1575 4300) $PN 1
J 0
(-1570 4262);
DISPLAY 0.617021 (-1570 4262);
PAINT ORANGE (-1570 4262);
FORCEPROP 1 LAST TOLERANCE 1.0%
J 0
(-1530 4225);
DISPLAY 0.617021 (-1530 4225);
PAINT SKYBLUE (-1530 4225);
FORCEPROP 1 LAST WATTAGE 1/16W
J 0
(-1535 4175);
DISPLAY 0.617021 (-1535 4175);
PAINT SKYBLUE (-1535 4175);
FORCEPROP 1 LAST VALUE 2.26K
J 0
(-1530 4275);
DISPLAY 0.617021 (-1530 4275);
PAINT SKYBLUE (-1530 4275);
FORCEPROP 1 LAST LOCATION R4E20
J 0
(-1530 4325);
DISPLAY 0.617021 (-1530 4325);
PAINT AQUA (-1530 4325);
FORCEPROP 1 LAST MATERIAL EMPTY
R 1
J 0
(-1385 4125);
DISPLAY 0.617021 (-1385 4125);
PAINT RED (-1385 4125);
FORCEPROP 2 LAST CDS_LIB mstr_discrete
J 0
(-1575 4200);
PAINT ORANGE (-1575 4200);
DISPLAY INVISIBLE (-1575 4200);
FORCEPROP 2 LAST ROOM PVCCIN_CPU0_VR
J 0
(-1725 4350);
DISPLAY 1.361702 (-1725 4350);
PAINT ORANGE (-1725 4350);
DISPLAY INVISIBLE (-1725 4350);
FORCEPROP 1 LAST PATH I116
J 0
(-1525 4375);
DISPLAY 0.978723 (-1525 4375);
PAINT WHITE (-1525 4375);
DISPLAY INVISIBLE (-1525 4375);
FORCEPROP 2 LAST SEC 1
J 0
(-1525 4425);
DISPLAY 0.680851 (-1525 4425);
PAINT MONO (-1525 4425);
DISPLAY INVISIBLE (-1525 4425);
FORCEPROP 2 LAST SEC_TYPE 0402
J 0
(-1525 4425);
DISPLAY 1.021277 (-1525 4425);
PAINT ORANGE (-1525 4425);
DISPLAY INVISIBLE (-1525 4425);
FORCEADD OFFPAGE..2
(-1050 3075);
FORCEPROP 2 LAST $XR0 95 
J 0
(-861 3075);
DISPLAY 0.638298 (-861 3075);
PAINT MONO (-861 3075);
FORCEPROP 1 LAST COMMENT_BODY TRUE
J 0
(-1095 2980);
DISPLAY 1.170213 (-1095 2980);
PAINT GREEN (-1095 2980);
DISPLAY INVISIBLE (-1095 2980);
FORCEPROP 1 LAST OFFPAGE TRUE
J 0
(-725 2950);
DISPLAY 1.170213 (-725 2950);
PAINT GREEN (-725 2950);
DISPLAY INVISIBLE (-725 2950);
FORCEPROP 2 LAST ROOM PVCCIN_CPU0_VR
J 0
(-1475 3150);
DISPLAY 1.361702 (-1475 3150);
PAINT ORANGE (-1475 3150);
DISPLAY INVISIBLE (-1475 3150);
FORCEPROP 2 LAST CDS_LIB mstr_standard
J 0
(-1050 3075);
PAINT ORANGE (-1050 3075);
DISPLAY INVISIBLE (-1050 3075);
FORCEPROP 2 LAST PATH I118
J 0
(-875 3150);
DISPLAY 1.021277 (-875 3150);
PAINT ORANGE (-875 3150);
DISPLAY INVISIBLE (-875 3150);
FORCEADD OFFPAGE..2
(-1050 2275);
FORCEPROP 2 LAST $XR0 204 
J 0
(-861 2275);
DISPLAY 0.638298 (-861 2275);
PAINT MONO (-861 2275);
FORCEPROP 1 LAST COMMENT_BODY TRUE
J 0
(-1095 2180);
DISPLAY 1.170213 (-1095 2180);
PAINT GREEN (-1095 2180);
DISPLAY INVISIBLE (-1095 2180);
FORCEPROP 1 LAST OFFPAGE TRUE
J 0
(-725 2150);
DISPLAY 1.170213 (-725 2150);
PAINT GREEN (-725 2150);
DISPLAY INVISIBLE (-725 2150);
FORCEPROP 2 LAST ROOM PVCCIN_CPU0_VR
J 0
(-1475 2350);
DISPLAY 1.361702 (-1475 2350);
PAINT ORANGE (-1475 2350);
DISPLAY INVISIBLE (-1475 2350);
FORCEPROP 2 LAST CDS_LIB mstr_standard
J 0
(-1050 2275);
PAINT ORANGE (-1050 2275);
DISPLAY INVISIBLE (-1050 2275);
FORCEPROP 2 LAST PATH I12
J 0
(-875 2350);
DISPLAY 1.021277 (-875 2350);
PAINT ORANGE (-875 2350);
DISPLAY INVISIBLE (-875 2350);
FORCEADD RES..2
(-4400 925);
FORCEPROP 1 LASTPIN (-4400 1025) $PN 1
J 0
(-4395 987);
DISPLAY 0.617021 (-4395 987);
PAINT ORANGE (-4395 987);
FORCEPROP 1 LASTPIN (-4400 825) $PN 2
J 0
(-4395 835);
DISPLAY 0.617021 (-4395 835);
PAINT ORANGE (-4395 835);
FORCEPROP 1 LAST WATTAGE 1/16W
J 0
(-4360 900);
DISPLAY 0.617021 (-4360 900);
PAINT SKYBLUE (-4360 900);
FORCEPROP 1 LAST MATERIAL CHIP
J 0
(-4360 850);
DISPLAY 0.617021 (-4360 850);
PAINT SKYBLUE (-4360 850);
FORCEPROP 1 LAST PACK_TYPE 0402
J 0
(-4360 750);
DISPLAY 0.617021 (-4360 750);
PAINT SKYBLUE (-4360 750);
FORCEPROP 1 LAST TOLERANCE 1%
J 0
(-4355 950);
DISPLAY 0.617021 (-4355 950);
PAINT SKYBLUE (-4355 950);
FORCEPROP 1 LAST VALUE 4.02K
J 0
(-4355 1000);
DISPLAY 0.617021 (-4355 1000);
PAINT SKYBLUE (-4355 1000);
FORCEPROP 1 LAST LOCATION R6P27
J 0
(-4355 1050);
DISPLAY 0.617021 (-4355 1050);
PAINT AQUA (-4355 1050);
FORCEPROP 1 LAST PART_NUMBER G21796-082
J 0
(-4360 800);
DISPLAY 0.617021 (-4360 800);
PAINT BLUE (-4360 800);
FORCEPROP 2 LAST CDS_LIB mstr_discrete
J 0
(-4400 925);
PAINT ORANGE (-4400 925);
DISPLAY INVISIBLE (-4400 925);
FORCEPROP 0 LAST ROOM PVCCIN_CPU0_VR
J 0
(-4350 1150);
DISPLAY 1.021277 (-4350 1150);
PAINT ORANGE (-4350 1150);
DISPLAY INVISIBLE (-4350 1150);
FORCEPROP 1 LAST PATH I120
J 0
(-4350 1100);
DISPLAY 0.978723 (-4350 1100);
PAINT WHITE (-4350 1100);
DISPLAY INVISIBLE (-4350 1100);
FORCEPROP 2 LAST CDS_LOCATION R6P27
J 0
(-4355 1050);
DISPLAY 0.617021 (-4355 1050);
PAINT AQUA (-4355 1050);
DISPLAY INVISIBLE (-4355 1050);
FORCEPROP 2 LAST SEC 1
J 0
(-4350 1150);
PAINT MONO (-4350 1150);
DISPLAY INVISIBLE (-4350 1150);
FORCEPROP 2 LAST SEC_TYPE 0402
J 0
(-4350 1150);
DISPLAY 1.021277 (-4350 1150);
PAINT ORANGE (-4350 1150);
DISPLAY INVISIBLE (-4350 1150);
FORCEADD RES..2
(-4725 900);
FORCEPROP 1 LAST TOLERANCE 1%
J 0
(-4680 925);
DISPLAY 0.617021 (-4680 925);
PAINT SKYBLUE (-4680 925);
FORCEPROP 1 LASTPIN (-4725 800) $PN 2
J 0
(-4720 810);
DISPLAY 0.617021 (-4720 810);
PAINT ORANGE (-4720 810);
FORCEPROP 1 LASTPIN (-4725 1000) $PN 1
J 0
(-4720 962);
DISPLAY 0.617021 (-4720 962);
PAINT ORANGE (-4720 962);
FORCEPROP 1 LAST WATTAGE 1/16W
J 0
(-4685 875);
DISPLAY 0.617021 (-4685 875);
PAINT SKYBLUE (-4685 875);
FORCEPROP 1 LAST MATERIAL CHIP
J 0
(-4685 825);
DISPLAY 0.617021 (-4685 825);
PAINT SKYBLUE (-4685 825);
FORCEPROP 1 LAST PACK_TYPE 0402
J 0
(-4685 725);
DISPLAY 0.617021 (-4685 725);
PAINT SKYBLUE (-4685 725);
FORCEPROP 1 LAST VALUE 4.02K
J 0
(-4680 975);
DISPLAY 0.617021 (-4680 975);
PAINT SKYBLUE (-4680 975);
FORCEPROP 1 LAST PART_NUMBER G21796-082
J 0
(-4685 775);
DISPLAY 0.617021 (-4685 775);
PAINT BLUE (-4685 775);
FORCEPROP 1 LAST LOCATION R6P28
J 0
(-4680 1025);
DISPLAY 0.617021 (-4680 1025);
PAINT AQUA (-4680 1025);
FORCEPROP 2 LAST CDS_LIB mstr_discrete
J 0
(-4725 900);
PAINT ORANGE (-4725 900);
DISPLAY INVISIBLE (-4725 900);
FORCEPROP 2 LAST SEC_TYPE 0402
J 0
(-4675 1125);
DISPLAY 1.021277 (-4675 1125);
PAINT ORANGE (-4675 1125);
DISPLAY INVISIBLE (-4675 1125);
FORCEPROP 2 LAST SEC 1
J 0
(-4675 1125);
PAINT MONO (-4675 1125);
DISPLAY INVISIBLE (-4675 1125);
FORCEPROP 2 LAST CDS_LOCATION R6P28
J 0
(-4680 1025);
DISPLAY 0.617021 (-4680 1025);
PAINT AQUA (-4680 1025);
DISPLAY INVISIBLE (-4680 1025);
FORCEPROP 1 LAST PATH I121
J 0
(-4675 1075);
DISPLAY 0.978723 (-4675 1075);
PAINT WHITE (-4675 1075);
DISPLAY INVISIBLE (-4675 1075);
FORCEPROP 0 LAST ROOM PVCCIN_CPU0_VR
J 0
(-4675 1125);
DISPLAY 1.021277 (-4675 1125);
PAINT ORANGE (-4675 1125);
DISPLAY INVISIBLE (-4675 1125);
FORCEADD CONN3_C95678002..1
(-3150 825);
FORCEPROP 1 LAST MATERIAL CONN
J 0
(-3200 975);
DISPLAY 0.617021 (-3200 975);
PAINT SKYBLUE (-3200 975);
FORCEPROP 1 LAST LOCATION J8D4
J 0
(-3200 1050);
DISPLAY 0.617021 (-3200 1050);
PAINT AQUA (-3200 1050);
FORCEPROP 1 LAST PART_NUMBER C95678-002
J 0
(-3200 650);
DISPLAY 0.617021 (-3200 650);
PAINT BLUE (-3200 650);
FORCEPROP 2 LASTPIN (-3050 875) $PN 1
J 0
(-3040 885);
DISPLAY 0.617021 (-3040 885);
PAINT ORANGE (-3040 885);
FORCEPROP 2 LASTPIN (-3050 775) $PN 3
J 0
(-3040 785);
DISPLAY 0.617021 (-3040 785);
PAINT ORANGE (-3040 785);
FORCEPROP 2 LASTPIN (-3050 825) $PN 2
J 0
(-3040 835);
DISPLAY 0.617021 (-3040 835);
PAINT ORANGE (-3040 835);
FORCEPROP 2 LAST CDS_LIB mstr_conn
J 0
(-3150 825);
PAINT ORANGE (-3150 825);
DISPLAY INVISIBLE (-3150 825);
FORCEPROP 2 LAST SEC 1
J 0
(-3200 1100);
DISPLAY 0.680851 (-3200 1100);
PAINT MONO (-3200 1100);
DISPLAY INVISIBLE (-3200 1100);
FORCEPROP 2 LAST ROOM SMBUS
J 0
(-3200 1075);
DISPLAY 1.021277 (-3200 1075);
PAINT ORANGE (-3200 1075);
DISPLAY INVISIBLE (-3200 1075);
FORCEPROP 2 LAST CDS_LOCATION J8D4
J 0
(-3200 1050);
DISPLAY 0.617021 (-3200 1050);
PAINT AQUA (-3200 1050);
DISPLAY INVISIBLE (-3200 1050);
FORCEPROP 2 LAST BOM_COST SM_CONTROLLER
J 0
(-3200 1125);
DISPLAY 1.021277 (-3200 1125);
PAINT ORANGE (-3200 1125);
DISPLAY INVISIBLE (-3200 1125);
FORCEPROP 2 LAST SEC_TYPE PIP
J 0
(-3200 1100);
DISPLAY 1.021277 (-3200 1100);
PAINT ORANGE (-3200 1100);
DISPLAY INVISIBLE (-3200 1100);
FORCEPROP 1 LAST PACK_TYPE PIP
J 0
(-3200 1075);
DISPLAY 0.978723 (-3200 1075);
PAINT SKYBLUE (-3200 1075);
DISPLAY INVISIBLE (-3200 1075);
FORCEPROP 1 LAST PATH I122
J 0
(-2750 975);
DISPLAY 0.978723 (-2750 975);
PAINT BLUE (-2750 975);
DISPLAY INVISIBLE (-2750 975);
FORCEADD GND..1
(-2900 775);
FORCEPROP 3 LASTPIN (-2900 825) SIG_NAME GND\g
J 0
(-2890 835);
DISPLAY 0.659574 (-2890 835);
PAINT MONO (-2890 835);
DISPLAY INVISIBLE (-2890 835);
FORCEPROP 1 LAST HDL_POWER GND
J 0
(-2900 925);
DISPLAY 1.468085 (-2900 925);
PAINT GREEN (-2900 925);
DISPLAY INVISIBLE (-2900 925);
FORCEPROP 1 LAST BODY_TYPE PLUMBING
J 0
(-2945 732);
DISPLAY 0.340426 (-2945 732);
PAINT GREEN (-2945 732);
DISPLAY INVISIBLE (-2945 732);
FORCEPROP 1 LAST SIZE 1B
J 0
(-2825 725);
DISPLAY 1.468085 (-2825 725);
PAINT GREEN (-2825 725);
DISPLAY INVISIBLE (-2825 725);
FORCEPROP 2 LAST CDS_LIB mstr_symbols
J 0
(-2900 775);
PAINT MONO (-2900 775);
DISPLAY INVISIBLE (-2900 775);
FORCEPROP 1 LAST PATH I123
J 0
(-2825 775);
DISPLAY 0.872340 (-2825 775);
PAINT AQUA (-2825 775);
DISPLAY INVISIBLE (-2825 775);
FORCEPROP 1 LAST VOLTAGE 0
J 0
(-2900 775);
PAINT SKYBLUE (-2900 775);
DISPLAY INVISIBLE (-2900 775);
FORCEADD RES..1
(-1125 3325);
FORCEPROP 1 LAST WATTAGE 1/16W
J 2
(-1150 3175);
DISPLAY 0.617021 (-1150 3175);
PAINT SKYBLUE (-1150 3175);
FORCEPROP 1 LAST VALUE 22.1
J 2
(-1150 3225);
DISPLAY 0.617021 (-1150 3225);
PAINT SKYBLUE (-1150 3225);
FORCEPROP 1 LAST LOCATION R4D63
J 0
(-1175 3375);
DISPLAY 0.617021 (-1175 3375);
PAINT AQUA (-1175 3375);
FORCEPROP 1 LAST MATERIAL CHIP
J 0
(-1125 3175);
DISPLAY 0.617021 (-1125 3175);
PAINT SKYBLUE (-1125 3175);
FORCEPROP 1 LAST TOLERANCE 1.0%
J 0
(-1125 3225);
DISPLAY 0.617021 (-1125 3225);
PAINT SKYBLUE (-1125 3225);
FORCEPROP 1 LAST PART_NUMBER G21796-250
J 0
(-1175 3425);
DISPLAY 0.617021 (-1175 3425);
PAINT BLUE (-1175 3425);
FORCEPROP 1 LAST PACK_TYPE 0402
J 0
(-875 3175);
DISPLAY 0.617021 (-875 3175);
PAINT SKYBLUE (-875 3175);
FORCEPROP 2 LAST CDS_LIB mstr_discrete
J 0
(-1125 3325);
PAINT MONO (-1125 3325);
DISPLAY INVISIBLE (-1125 3325);
FORCEPROP 1 LASTPIN (-1225 3325) $PN 1
J 0
(-1213 3337);
DISPLAY 0.787234 (-1213 3337);
PAINT ORANGE (-1213 3337);
DISPLAY INVISIBLE (-1213 3337);
FORCEPROP 1 LASTPIN (-1025 3325) $PN 2
J 0
(-1063 3337);
DISPLAY 0.787234 (-1063 3337);
PAINT ORANGE (-1063 3337);
DISPLAY INVISIBLE (-1063 3337);
FORCEPROP 2 LAST ROOM PVCCIN_CPU0_VR
J 0
(-1025 3425);
DISPLAY 1.361702 (-1025 3425);
PAINT ORANGE (-1025 3425);
DISPLAY INVISIBLE (-1025 3425);
FORCEPROP 1 LAST PATH I124
J 0
(-1175 3475);
DISPLAY 0.978723 (-1175 3475);
PAINT WHITE (-1175 3475);
DISPLAY INVISIBLE (-1175 3475);
FORCEPROP 2 LAST CDS_LOCATION R4D63
J 0
(-1175 3375);
DISPLAY 0.617021 (-1175 3375);
PAINT AQUA (-1175 3375);
DISPLAY INVISIBLE (-1175 3375);
FORCEPROP 2 LAST CDS_SEC 1
J 0
(-1175 3525);
PAINT MONO (-1175 3525);
DISPLAY INVISIBLE (-1175 3525);
FORCEPROP 2 LAST $SEC 1
J 0
(-1175 3525);
PAINT MONO (-1175 3525);
DISPLAY INVISIBLE (-1175 3525);
FORCEADD CAP..1
(-1450 2075);
FORCEPROP 1 LASTPIN (-1450 1975) $PN 2
J 0
(-1440 1955);
DISPLAY 0.617021 (-1440 1955);
PAINT ORANGE (-1440 1955);
FORCEPROP 1 LAST MATERIAL X7R
J 0
(-1400 1975);
DISPLAY 0.617021 (-1400 1975);
PAINT SKYBLUE (-1400 1975);
FORCEPROP 1 LAST PACK_TYPE 0402LF
J 0
(-1400 1875);
DISPLAY 0.617021 (-1400 1875);
PAINT SKYBLUE (-1400 1875);
FORCEPROP 1 LAST PART_NUMBER A36096-046
J 0
(-1400 1925);
DISPLAY 0.617021 (-1400 1925);
PAINT BLUE (-1400 1925);
FORCEPROP 1 LAST TOLERANCE 10%
J 0
(-1400 2025);
DISPLAY 0.617021 (-1400 2025);
PAINT SKYBLUE (-1400 2025);
FORCEPROP 1 LAST VOLTAGE 50V
J 0
(-1400 2075);
DISPLAY 0.617021 (-1400 2075);
PAINT SKYBLUE (-1400 2075);
FORCEPROP 1 LASTPIN (-1450 2175) $PN 1
J 0
(-1440 2155);
DISPLAY 0.617021 (-1440 2155);
PAINT ORANGE (-1440 2155);
FORCEPROP 1 LAST VALUE 1000PF
J 0
(-1400 2125);
DISPLAY 0.617021 (-1400 2125);
PAINT SKYBLUE (-1400 2125);
FORCEPROP 1 LAST LOCATION C4D42
J 0
(-1400 2175);
DISPLAY 0.617021 (-1400 2175);
PAINT AQUA (-1400 2175);
FORCEPROP 2 LAST CDS_LIB mstr_discrete
J 0
(-1450 2075);
PAINT MONO (-1450 2075);
DISPLAY INVISIBLE (-1450 2075);
FORCEPROP 2 LAST SEC 1
J 0
(-1400 2275);
DISPLAY 0.680851 (-1400 2275);
PAINT MONO (-1400 2275);
DISPLAY INVISIBLE (-1400 2275);
FORCEPROP 2 LAST CDS_LOCATION C4D42
J 0
(-1400 2175);
DISPLAY 0.617021 (-1400 2175);
PAINT AQUA (-1400 2175);
DISPLAY INVISIBLE (-1400 2175);
FORCEPROP 1 LAST PATH I125
J 0
(-1400 2225);
DISPLAY 0.978723 (-1400 2225);
PAINT WHITE (-1400 2225);
DISPLAY INVISIBLE (-1400 2225);
FORCEPROP 2 LAST SEC_TYPE 0402LF
J 0
(-1400 2275);
DISPLAY 1.021277 (-1400 2275);
PAINT ORANGE (-1400 2275);
DISPLAY INVISIBLE (-1400 2275);
FORCEPROP 0 LAST ROOM PVCCIN_CPU0_VR
J 0
(-1400 2275);
DISPLAY 1.021277 (-1400 2275);
PAINT ORANGE (-1400 2275);
DISPLAY INVISIBLE (-1400 2275);
FORCEADD GND..1
(-1450 1850);
FORCEPROP 3 LASTPIN (-1450 1900) SIG_NAME GND\g
J 0
(-1440 1910);
DISPLAY 0.659574 (-1440 1910);
PAINT MONO (-1440 1910);
DISPLAY INVISIBLE (-1440 1910);
FORCEPROP 1 LAST HDL_POWER GND
J 0
(-1450 2000);
DISPLAY 1.170213 (-1450 2000);
PAINT GREEN (-1450 2000);
DISPLAY INVISIBLE (-1450 2000);
FORCEPROP 1 LAST BODY_TYPE PLUMBING
J 0
(-1495 1807);
DISPLAY 0.340426 (-1495 1807);
PAINT GREEN (-1495 1807);
DISPLAY INVISIBLE (-1495 1807);
FORCEPROP 2 LAST ROOM PVCCIN_CPU0_VR
J 0
(-2025 1925);
DISPLAY 1.361702 (-2025 1925);
PAINT ORANGE (-2025 1925);
DISPLAY INVISIBLE (-2025 1925);
FORCEPROP 2 LAST CDS_LIB mstr_symbols
J 0
(-1450 1850);
PAINT MONO (-1450 1850);
DISPLAY INVISIBLE (-1450 1850);
FORCEPROP 1 LAST VOLTAGE 0
J 0
(-1450 1850);
PAINT SKYBLUE (-1450 1850);
DISPLAY INVISIBLE (-1450 1850);
FORCEPROP 1 LAST PATH I126
J 0
(-1375 1850);
DISPLAY 0.872340 (-1375 1850);
PAINT AQUA (-1375 1850);
DISPLAY INVISIBLE (-1375 1850);
FORCEPROP 1 LAST SIZE 1B
J 0
(-1375 1800);
DISPLAY 1.170213 (-1375 1800);
PAINT AQUA (-1375 1800);
DISPLAY INVISIBLE (-1375 1800);
FORCEADD RES..1
(-1800 2675);
FORCEPROP 1 LAST WATTAGE 1/16W
J 2
(-1950 2575);
DISPLAY 0.617021 (-1950 2575);
PAINT SKYBLUE (-1950 2575);
FORCEPROP 1 LASTPIN (-1900 2675) $PN 1
J 0
(-1888 2687);
DISPLAY 0.617021 (-1888 2687);
PAINT ORANGE (-1888 2687);
FORCEPROP 1 LAST VALUE 33.2
J 2
(-1825 2575);
DISPLAY 0.617021 (-1825 2575);
PAINT SKYBLUE (-1825 2575);
FORCEPROP 1 LAST TOLERANCE 1%
J 0
(-1800 2575);
DISPLAY 0.617021 (-1800 2575);
PAINT SKYBLUE (-1800 2575);
FORCEPROP 1 LAST PART_NUMBER G21796-074
J 0
(-1975 2625);
DISPLAY 0.617021 (-1975 2625);
PAINT BLUE (-1975 2625);
FORCEPROP 1 LAST LOCATION R4D65
J 0
(-1900 2725);
DISPLAY 0.617021 (-1900 2725);
PAINT AQUA (-1900 2725);
FORCEPROP 1 LASTPIN (-1700 2675) $PN 2
J 0
(-1738 2687);
DISPLAY 0.617021 (-1738 2687);
PAINT ORANGE (-1738 2687);
FORCEPROP 1 LAST PACK_TYPE 0402
J 0
(-1700 2575);
DISPLAY 0.617021 (-1700 2575);
PAINT SKYBLUE (-1700 2575);
FORCEPROP 1 LAST MATERIAL CHIP
J 0
(-1600 2575);
DISPLAY 0.617021 (-1600 2575);
PAINT SKYBLUE (-1600 2575);
FORCEPROP 2 LAST CDS_LOCATION R4D65
J 0
(-1900 2725);
DISPLAY 0.617021 (-1900 2725);
PAINT AQUA (-1900 2725);
DISPLAY INVISIBLE (-1900 2725);
FORCEPROP 2 LAST CDS_LIB mstr_discrete
J 0
(-1800 2675);
PAINT MONO (-1800 2675);
DISPLAY INVISIBLE (-1800 2675);
FORCEPROP 1 LAST PATH I127
J 0
(-1850 2825);
DISPLAY 0.978723 (-1850 2825);
PAINT WHITE (-1850 2825);
DISPLAY INVISIBLE (-1850 2825);
FORCEPROP 2 LAST SEC 1
J 0
(-1850 2875);
DISPLAY 0.680851 (-1850 2875);
PAINT MONO (-1850 2875);
DISPLAY INVISIBLE (-1850 2875);
FORCEPROP 2 LAST SEC_TYPE 0402
J 0
(-1850 2875);
DISPLAY 1.021277 (-1850 2875);
PAINT ORANGE (-1850 2875);
DISPLAY INVISIBLE (-1850 2875);
FORCEADD RES..1
(-2400 2975);
FORCEPROP 1 LAST WATTAGE 1/16W
J 2
(-2425 2825);
DISPLAY 0.617021 (-2425 2825);
PAINT SKYBLUE (-2425 2825);
FORCEPROP 1 LASTPIN (-2500 2975) $PN 1
J 0
(-2488 2987);
DISPLAY 0.617021 (-2488 2987);
PAINT ORANGE (-2488 2987);
FORCEPROP 1 LAST VALUE 33.2
J 2
(-2425 2875);
DISPLAY 0.617021 (-2425 2875);
PAINT SKYBLUE (-2425 2875);
FORCEPROP 1 LAST LOCATION R6P45
J 0
(-2450 3025);
DISPLAY 0.617021 (-2450 3025);
PAINT AQUA (-2450 3025);
FORCEPROP 1 LASTPIN (-2300 2975) $PN 2
J 0
(-2338 2987);
DISPLAY 0.617021 (-2338 2987);
PAINT ORANGE (-2338 2987);
FORCEPROP 1 LAST TOLERANCE 1%
J 0
(-2400 2875);
DISPLAY 0.617021 (-2400 2875);
PAINT SKYBLUE (-2400 2875);
FORCEPROP 1 LAST MATERIAL CHIP
J 0
(-2400 2825);
DISPLAY 0.617021 (-2400 2825);
PAINT SKYBLUE (-2400 2825);
FORCEPROP 1 LAST PART_NUMBER G21796-074
J 0
(-2450 3075);
DISPLAY 0.617021 (-2450 3075);
PAINT BLUE (-2450 3075);
FORCEPROP 1 LAST PACK_TYPE 0402
J 0
(-2150 2825);
DISPLAY 0.617021 (-2150 2825);
PAINT SKYBLUE (-2150 2825);
FORCEPROP 2 LAST CDS_LOCATION R6P45
J 0
(-2450 3025);
DISPLAY 0.617021 (-2450 3025);
PAINT AQUA (-2450 3025);
DISPLAY INVISIBLE (-2450 3025);
FORCEPROP 2 LAST CDS_LIB mstr_discrete
J 0
(-2400 2975);
PAINT MONO (-2400 2975);
DISPLAY INVISIBLE (-2400 2975);
FORCEPROP 1 LAST PATH I128
J 0
(-2450 3125);
DISPLAY 0.978723 (-2450 3125);
PAINT WHITE (-2450 3125);
DISPLAY INVISIBLE (-2450 3125);
FORCEPROP 2 LAST SEC 1
J 0
(-2450 3175);
DISPLAY 0.680851 (-2450 3175);
PAINT MONO (-2450 3175);
DISPLAY INVISIBLE (-2450 3175);
FORCEPROP 2 LAST SEC_TYPE 0402
J 0
(-2450 3175);
DISPLAY 1.021277 (-2450 3175);
PAINT ORANGE (-2450 3175);
DISPLAY INVISIBLE (-2450 3175);
FORCEADD RES..1
(-5100 2225);
FORCEPROP 1 LAST WATTAGE 1/16W
J 2
(-5125 2075);
DISPLAY 0.617021 (-5125 2075);
PAINT SKYBLUE (-5125 2075);
FORCEPROP 1 LAST VALUE 0.0
J 2
(-5200 2125);
DISPLAY 0.617021 (-5200 2125);
PAINT SKYBLUE (-5200 2125);
FORCEPROP 1 LASTPIN (-5200 2225) $PN 1
J 0
(-5188 2237);
DISPLAY 0.617021 (-5188 2237);
PAINT ORANGE (-5188 2237);
FORCEPROP 1 LAST TOLERANCE 5%
J 0
(-5150 2125);
DISPLAY 0.617021 (-5150 2125);
PAINT SKYBLUE (-5150 2125);
FORCEPROP 1 LAST PART_NUMBER G21497-005
J 0
(-5250 2175);
DISPLAY 0.617021 (-5250 2175);
PAINT BLUE (-5250 2175);
FORCEPROP 1 LAST LOCATION R6P18
J 0
(-5150 2275);
DISPLAY 0.617021 (-5150 2275);
PAINT AQUA (-5150 2275);
FORCEPROP 1 LASTPIN (-5000 2225) $PN 2
J 0
(-5038 2237);
DISPLAY 0.617021 (-5038 2237);
PAINT ORANGE (-5038 2237);
FORCEPROP 1 LAST MATERIAL CHIP
J 0
(-5100 2075);
DISPLAY 0.617021 (-5100 2075);
PAINT SKYBLUE (-5100 2075);
FORCEPROP 1 LAST PACK_TYPE 0402
J 0
(-5025 2125);
DISPLAY 0.617021 (-5025 2125);
PAINT SKYBLUE (-5025 2125);
FORCEPROP 2 LAST CDS_LOCATION R6P18
J 0
(-5150 2275);
DISPLAY 0.617021 (-5150 2275);
PAINT AQUA (-5150 2275);
DISPLAY INVISIBLE (-5150 2275);
FORCEPROP 2 LAST SEC_TYPE 0402
J 0
(-5150 2425);
DISPLAY 1.021277 (-5150 2425);
PAINT ORANGE (-5150 2425);
DISPLAY INVISIBLE (-5150 2425);
FORCEPROP 2 LAST SEC 1
J 0
(-5150 2425);
PAINT MONO (-5150 2425);
DISPLAY INVISIBLE (-5150 2425);
FORCEPROP 1 LAST PATH I131
J 0
(-5150 2375);
DISPLAY 0.978723 (-5150 2375);
PAINT WHITE (-5150 2375);
DISPLAY INVISIBLE (-5150 2375);
FORCEPROP 2 LAST ROOM PVCCIN_CPU0_VR
J 0
(-5150 2325);
DISPLAY 1.361702 (-5150 2325);
PAINT ORANGE (-5150 2325);
DISPLAY INVISIBLE (-5150 2325);
FORCEPROP 2 LAST CDS_LIB mstr_discrete
J 0
(-5100 2225);
PAINT ORANGE (-5100 2225);
DISPLAY INVISIBLE (-5100 2225);
FORCEADD RES..2
(-4775 4350);
FORCEPROP 1 LAST MATERIAL CHIP
J 0
(-4735 4275);
DISPLAY 0.617021 (-4735 4275);
PAINT SKYBLUE (-4735 4275);
FORCEPROP 1 LAST PACK_TYPE 0402
J 0
(-4735 4175);
DISPLAY 0.617021 (-4735 4175);
PAINT SKYBLUE (-4735 4175);
FORCEPROP 1 LAST TOLERANCE 1%
J 0
(-4730 4375);
DISPLAY 0.617021 (-4730 4375);
PAINT SKYBLUE (-4730 4375);
FORCEPROP 1 LAST WATTAGE 1/16W
J 0
(-4735 4325);
DISPLAY 0.617021 (-4735 4325);
PAINT SKYBLUE (-4735 4325);
FORCEPROP 1 LAST VALUE 1.00K
J 0
(-4730 4425);
DISPLAY 0.617021 (-4730 4425);
PAINT SKYBLUE (-4730 4425);
FORCEPROP 1 LAST PART_NUMBER G21796-026
J 0
(-4735 4225);
DISPLAY 0.617021 (-4735 4225);
PAINT BLUE (-4735 4225);
FORCEPROP 1 LAST LOCATION R6P16
J 0
(-4730 4475);
DISPLAY 0.617021 (-4730 4475);
PAINT AQUA (-4730 4475);
FORCEPROP 1 LASTPIN (-4775 4250) $PN 2
J 0
(-4770 4260);
DISPLAY 0.787234 (-4770 4260);
PAINT ORANGE (-4770 4260);
DISPLAY INVISIBLE (-4770 4260);
FORCEPROP 2 LAST CDS_LIB mstr_discrete
J 0
(-4775 4350);
PAINT ORANGE (-4775 4350);
DISPLAY INVISIBLE (-4775 4350);
FORCEPROP 1 LASTPIN (-4775 4450) $PN 1
J 0
(-4770 4412);
DISPLAY 0.787234 (-4770 4412);
PAINT ORANGE (-4770 4412);
DISPLAY INVISIBLE (-4770 4412);
FORCEPROP 0 LAST ROOM BMC
J 0
(-4725 4575);
DISPLAY 0.617021 (-4725 4575);
PAINT ORANGE (-4725 4575);
DISPLAY INVISIBLE (-4725 4575);
FORCEPROP 1 LAST PATH I132
J 0
(-4725 4525);
DISPLAY 0.978723 (-4725 4525);
PAINT WHITE (-4725 4525);
DISPLAY INVISIBLE (-4725 4525);
FORCEPROP 2 LAST CDS_LOCATION R6P16
J 0
(-4730 4475);
DISPLAY 0.617021 (-4730 4475);
PAINT AQUA (-4730 4475);
DISPLAY INVISIBLE (-4730 4475);
FORCEPROP 2 LAST CDS_SEC 1
J 0
(-4725 4575);
PAINT MONO (-4725 4575);
DISPLAY INVISIBLE (-4725 4575);
FORCEPROP 2 LAST $SEC 1
J 0
(-4725 4575);
PAINT MONO (-4725 4575);
DISPLAY INVISIBLE (-4725 4575);
FORCEPROP 0 LAST BOM_COST SM_CONTROLLER
J 0
(-4725 4675);
DISPLAY 1.021277 (-4725 4675);
PAINT ORANGE (-4725 4675);
DISPLAY INVISIBLE (-4725 4675);
FORCEADD RES..2
(-6475 3625);
FORCEPROP 1 LAST PART_NUMBER G21497-005
J 0
(-6685 3625);
DISPLAY 0.617021 (-6685 3625);
PAINT BLUE (-6685 3625);
FORCEPROP 1 LASTPIN (-6475 3525) $PN 2
J 0
(-6470 3535);
DISPLAY 0.617021 (-6470 3535);
PAINT ORANGE (-6470 3535);
FORCEPROP 1 LAST MATERIAL CHIP
J 0
(-6435 3550);
DISPLAY 0.617021 (-6435 3550);
PAINT SKYBLUE (-6435 3550);
FORCEPROP 1 LAST PACK_TYPE 0402
J 0
(-6635 3675);
DISPLAY 0.617021 (-6635 3675);
PAINT SKYBLUE (-6635 3675);
FORCEPROP 1 LASTPIN (-6475 3725) $PN 1
J 0
(-6470 3687);
DISPLAY 0.617021 (-6470 3687);
PAINT ORANGE (-6470 3687);
FORCEPROP 1 LAST WATTAGE 1/16W
J 0
(-6435 3600);
DISPLAY 0.617021 (-6435 3600);
PAINT SKYBLUE (-6435 3600);
FORCEPROP 1 LAST TOLERANCE 5%
J 0
(-6430 3650);
DISPLAY 0.617021 (-6430 3650);
PAINT SKYBLUE (-6430 3650);
FORCEPROP 1 LAST VALUE 0.0
J 0
(-6430 3700);
DISPLAY 0.617021 (-6430 3700);
PAINT SKYBLUE (-6430 3700);
FORCEPROP 1 LAST LOCATION R6P42
J 0
(-6430 3750);
DISPLAY 0.617021 (-6430 3750);
PAINT AQUA (-6430 3750);
FORCEPROP 2 LAST CDS_LIB mstr_discrete
J 0
(-6475 3625);
PAINT ORANGE (-6475 3625);
DISPLAY INVISIBLE (-6475 3625);
FORCEPROP 2 LAST ROOM PVCCIN_CPU0_VR
J 0
(-6525 3725);
DISPLAY 1.361702 (-6525 3725);
PAINT ORANGE (-6525 3725);
DISPLAY INVISIBLE (-6525 3725);
FORCEPROP 2 LAST CDS_LOCATION R6P42
J 0
(-6430 3750);
DISPLAY 0.617021 (-6430 3750);
PAINT AQUA (-6430 3750);
DISPLAY INVISIBLE (-6430 3750);
FORCEPROP 1 LAST PATH I139
J 0
(-6425 3800);
DISPLAY 0.978723 (-6425 3800);
PAINT WHITE (-6425 3800);
DISPLAY INVISIBLE (-6425 3800);
FORCEPROP 2 LAST SEC 1
J 0
(-6425 3850);
PAINT MONO (-6425 3850);
DISPLAY INVISIBLE (-6425 3850);
FORCEPROP 2 LAST SEC_TYPE 0402
J 0
(-6425 3850);
DISPLAY 1.021277 (-6425 3850);
PAINT ORANGE (-6425 3850);
DISPLAY INVISIBLE (-6425 3850);
FORCEADD OFFPAGE..3
(-750 1775);
FORCEPROP 2 LAST $XR0 138 
J 0
(-536 1775);
DISPLAY 0.638298 (-536 1775);
PAINT MONO (-536 1775);
FORCEPROP 2 LAST $XR1 159 
J 0
(-416 1775);
DISPLAY 0.638298 (-416 1775);
PAINT MONO (-416 1775);
FORCEPROP 2 LAST $XR2 193 
J 0
(-296 1775);
DISPLAY 0.638298 (-296 1775);
PAINT MONO (-296 1775);
FORCEPROP 2 LAST $XR3 194 
J 0
(-536 1739);
DISPLAY 0.638298 (-536 1739);
PAINT MONO (-536 1739);
FORCEPROP 2 LAST $XR4 206 
J 0
(-416 1739);
DISPLAY 0.638298 (-416 1739);
PAINT MONO (-416 1739);
FORCEPROP 2 LAST $XR5 211 
J 0
(-296 1739);
DISPLAY 0.638298 (-296 1739);
PAINT MONO (-296 1739);
FORCEPROP 2 LAST $XR6 213 
J 0
(-536 1811);
DISPLAY 0.638298 (-536 1811);
PAINT MONO (-536 1811);
FORCEPROP 2 LAST $XR7 215 
J 0
(-416 1811);
DISPLAY 0.638298 (-416 1811);
PAINT MONO (-416 1811);
FORCEPROP 2 LAST $XR8 218 
J 0
(-296 1811);
DISPLAY 0.638298 (-296 1811);
PAINT MONO (-296 1811);
FORCEPROP 2 LAST $XR9 223 
J 0
(-536 1703);
DISPLAY 0.638298 (-536 1703);
PAINT MONO (-536 1703);
FORCEPROP 2 LAST $XR10 226 
J 0
(-416 1703);
DISPLAY 0.638298 (-416 1703);
PAINT MONO (-416 1703);
FORCEPROP 2 LAST $XR11 235 
J 0
(-296 1703);
DISPLAY 0.638298 (-296 1703);
PAINT MONO (-296 1703);
FORCEPROP 1 LAST COMMENT_BODY TRUE
J 0
(-800 1675);
DISPLAY 1.170213 (-800 1675);
PAINT GREEN (-800 1675);
DISPLAY INVISIBLE (-800 1675);
FORCEPROP 1 LAST OFFPAGE TRUE
J 0
(-425 1650);
DISPLAY 1.170213 (-425 1650);
PAINT GREEN (-425 1650);
DISPLAY INVISIBLE (-425 1650);
FORCEPROP 2 LAST ROOM PVCCIN_CPU0_VR
J 0
(-1150 1850);
DISPLAY 1.361702 (-1150 1850);
PAINT ORANGE (-1150 1850);
DISPLAY INVISIBLE (-1150 1850);
FORCEPROP 2 LAST CDS_LIB mstr_standard
J 0
(-750 1775);
PAINT ORANGE (-750 1775);
DISPLAY INVISIBLE (-750 1775);
FORCEPROP 2 LAST PATH I14
J 0
(-550 1850);
DISPLAY 1.021277 (-550 1850);
PAINT ORANGE (-550 1850);
DISPLAY INVISIBLE (-550 1850);
FORCEADD OFFPAGE..1
(-7400 3825);
FORCEPROP 2 LAST $XR0 201 
J 0
(-7682 3825);
DISPLAY 0.638298 (-7682 3825);
PAINT MONO (-7682 3825);
FORCEPROP 1 LAST COMMENT_BODY TRUE
J 0
(-7275 3725);
DISPLAY 1.170213 (-7275 3725);
PAINT GREEN (-7275 3725);
DISPLAY INVISIBLE (-7275 3725);
FORCEPROP 1 LAST OFFPAGE TRUE
J 0
(-7075 3700);
DISPLAY 1.170213 (-7075 3700);
PAINT GREEN (-7075 3700);
DISPLAY INVISIBLE (-7075 3700);
FORCEPROP 2 LAST ROOM PVCCIN_CPU0_VR
J 0
(-7950 3900);
DISPLAY 1.361702 (-7950 3900);
PAINT ORANGE (-7950 3900);
DISPLAY INVISIBLE (-7950 3900);
FORCEPROP 2 LAST CDS_LIB mstr_standard
J 0
(-7400 3825);
PAINT ORANGE (-7400 3825);
DISPLAY INVISIBLE (-7400 3825);
FORCEPROP 2 LAST PATH I146
J 0
(-7350 3900);
DISPLAY 1.021277 (-7350 3900);
PAINT ORANGE (-7350 3900);
DISPLAY INVISIBLE (-7350 3900);
FORCEADD RES..2
(-6000 3625);
FORCEPROP 1 LAST PACK_TYPE 0402
J 0
(-6185 3675);
DISPLAY 0.617021 (-6185 3675);
PAINT SKYBLUE (-6185 3675);
FORCEPROP 1 LAST PART_NUMBER G21497-005
J 0
(-6235 3625);
DISPLAY 0.617021 (-6235 3625);
PAINT BLUE (-6235 3625);
FORCEPROP 1 LASTPIN (-6000 3525) $PN 2
J 0
(-5995 3535);
DISPLAY 0.617021 (-5995 3535);
PAINT ORANGE (-5995 3535);
FORCEPROP 1 LAST MATERIAL CHIP
J 0
(-5960 3550);
DISPLAY 0.617021 (-5960 3550);
PAINT SKYBLUE (-5960 3550);
FORCEPROP 1 LAST TOLERANCE 5%
J 0
(-5955 3650);
DISPLAY 0.617021 (-5955 3650);
PAINT SKYBLUE (-5955 3650);
FORCEPROP 1 LASTPIN (-6000 3725) $PN 1
J 0
(-5995 3687);
DISPLAY 0.617021 (-5995 3687);
PAINT ORANGE (-5995 3687);
FORCEPROP 1 LAST WATTAGE 1/16W
J 0
(-5960 3600);
DISPLAY 0.617021 (-5960 3600);
PAINT SKYBLUE (-5960 3600);
FORCEPROP 1 LAST VALUE 0.0
J 0
(-5955 3700);
DISPLAY 0.617021 (-5955 3700);
PAINT SKYBLUE (-5955 3700);
FORCEPROP 1 LAST LOCATION R6P38
J 0
(-5955 3750);
DISPLAY 0.617021 (-5955 3750);
PAINT AQUA (-5955 3750);
FORCEPROP 2 LAST ROOM PVCCIN_CPU0_VR
J 0
(-6050 3725);
DISPLAY 1.361702 (-6050 3725);
PAINT ORANGE (-6050 3725);
DISPLAY INVISIBLE (-6050 3725);
FORCEPROP 2 LAST CDS_LIB mstr_discrete
J 0
(-6000 3625);
PAINT ORANGE (-6000 3625);
DISPLAY INVISIBLE (-6000 3625);
FORCEPROP 2 LAST CDS_LOCATION R6P38
J 0
(-5955 3750);
DISPLAY 0.617021 (-5955 3750);
PAINT AQUA (-5955 3750);
DISPLAY INVISIBLE (-5955 3750);
FORCEPROP 1 LAST PATH I147
J 0
(-5950 3800);
DISPLAY 0.978723 (-5950 3800);
PAINT WHITE (-5950 3800);
DISPLAY INVISIBLE (-5950 3800);
FORCEPROP 2 LAST SEC 1
J 0
(-5950 3850);
PAINT MONO (-5950 3850);
DISPLAY INVISIBLE (-5950 3850);
FORCEPROP 2 LAST SEC_TYPE 0402
J 0
(-5950 3850);
DISPLAY 1.021277 (-5950 3850);
PAINT ORANGE (-5950 3850);
DISPLAY INVISIBLE (-5950 3850);
FORCEADD RES..2
(-5575 3625);
FORCEPROP 1 LAST PACK_TYPE 0402
J 0
(-5710 3675);
DISPLAY 0.617021 (-5710 3675);
PAINT SKYBLUE (-5710 3675);
FORCEPROP 1 LAST PART_NUMBER G21497-005
J 0
(-5785 3625);
DISPLAY 0.617021 (-5785 3625);
PAINT BLUE (-5785 3625);
FORCEPROP 1 LASTPIN (-5575 3525) $PN 2
J 0
(-5570 3535);
DISPLAY 0.617021 (-5570 3535);
PAINT ORANGE (-5570 3535);
FORCEPROP 1 LAST MATERIAL CHIP
J 0
(-5535 3550);
DISPLAY 0.617021 (-5535 3550);
PAINT SKYBLUE (-5535 3550);
FORCEPROP 1 LASTPIN (-5575 3725) $PN 1
J 0
(-5570 3687);
DISPLAY 0.617021 (-5570 3687);
PAINT ORANGE (-5570 3687);
FORCEPROP 1 LAST LOCATION R6P34
J 0
(-5530 3750);
DISPLAY 0.617021 (-5530 3750);
PAINT AQUA (-5530 3750);
FORCEPROP 1 LAST VALUE 0.0
J 0
(-5530 3700);
DISPLAY 0.617021 (-5530 3700);
PAINT SKYBLUE (-5530 3700);
FORCEPROP 1 LAST TOLERANCE 5%
J 0
(-5530 3650);
DISPLAY 0.617021 (-5530 3650);
PAINT SKYBLUE (-5530 3650);
FORCEPROP 1 LAST WATTAGE 1/16W
J 0
(-5535 3600);
DISPLAY 0.617021 (-5535 3600);
PAINT SKYBLUE (-5535 3600);
FORCEPROP 2 LAST CDS_LIB mstr_discrete
J 0
(-5575 3625);
PAINT ORANGE (-5575 3625);
DISPLAY INVISIBLE (-5575 3625);
FORCEPROP 2 LAST ROOM PVCCIN_CPU0_VR
J 0
(-5625 3725);
DISPLAY 1.361702 (-5625 3725);
PAINT ORANGE (-5625 3725);
DISPLAY INVISIBLE (-5625 3725);
FORCEPROP 2 LAST CDS_LOCATION R6P34
J 0
(-5530 3750);
DISPLAY 0.617021 (-5530 3750);
PAINT AQUA (-5530 3750);
DISPLAY INVISIBLE (-5530 3750);
FORCEPROP 1 LAST PATH I148
J 0
(-5525 3800);
DISPLAY 0.978723 (-5525 3800);
PAINT WHITE (-5525 3800);
DISPLAY INVISIBLE (-5525 3800);
FORCEPROP 2 LAST SEC_TYPE 0402
J 0
(-5525 3850);
DISPLAY 1.021277 (-5525 3850);
PAINT ORANGE (-5525 3850);
DISPLAY INVISIBLE (-5525 3850);
FORCEPROP 2 LAST SEC 1
J 0
(-5525 3850);
PAINT MONO (-5525 3850);
DISPLAY INVISIBLE (-5525 3850);
FORCEADD RES..2
(-5175 3625);
FORCEPROP 1 LASTPIN (-5175 3525) $PN 2
J 0
(-5170 3535);
DISPLAY 0.617021 (-5170 3535);
PAINT ORANGE (-5170 3535);
FORCEPROP 1 LAST PACK_TYPE 0402
J 0
(-5285 3675);
DISPLAY 0.617021 (-5285 3675);
PAINT SKYBLUE (-5285 3675);
FORCEPROP 1 LASTPIN (-5175 3725) $PN 1
J 0
(-5170 3687);
DISPLAY 0.617021 (-5170 3687);
PAINT ORANGE (-5170 3687);
FORCEPROP 1 LAST WATTAGE 1/16W
J 0
(-5135 3600);
DISPLAY 0.617021 (-5135 3600);
PAINT SKYBLUE (-5135 3600);
FORCEPROP 1 LAST MATERIAL CHIP
J 0
(-5135 3550);
DISPLAY 0.617021 (-5135 3550);
PAINT SKYBLUE (-5135 3550);
FORCEPROP 1 LAST TOLERANCE 5%
J 0
(-5130 3650);
DISPLAY 0.617021 (-5130 3650);
PAINT SKYBLUE (-5130 3650);
FORCEPROP 1 LAST VALUE 0.0
J 0
(-5130 3700);
DISPLAY 0.617021 (-5130 3700);
PAINT SKYBLUE (-5130 3700);
FORCEPROP 1 LAST PART_NUMBER G21497-005
J 0
(-5385 3625);
DISPLAY 0.617021 (-5385 3625);
PAINT BLUE (-5385 3625);
FORCEPROP 1 LAST LOCATION R6P30
J 0
(-5130 3750);
DISPLAY 0.617021 (-5130 3750);
PAINT AQUA (-5130 3750);
FORCEPROP 2 LAST CDS_LIB mstr_discrete
J 0
(-5175 3625);
PAINT ORANGE (-5175 3625);
DISPLAY INVISIBLE (-5175 3625);
FORCEPROP 2 LAST ROOM PVCCIN_CPU0_VR
J 0
(-5225 3725);
DISPLAY 1.361702 (-5225 3725);
PAINT ORANGE (-5225 3725);
DISPLAY INVISIBLE (-5225 3725);
FORCEPROP 2 LAST CDS_LOCATION R6P30
J 0
(-5130 3750);
DISPLAY 0.617021 (-5130 3750);
PAINT AQUA (-5130 3750);
DISPLAY INVISIBLE (-5130 3750);
FORCEPROP 1 LAST PATH I149
J 0
(-5125 3800);
DISPLAY 0.978723 (-5125 3800);
PAINT WHITE (-5125 3800);
DISPLAY INVISIBLE (-5125 3800);
FORCEPROP 2 LAST SEC 1
J 0
(-5125 3850);
PAINT MONO (-5125 3850);
DISPLAY INVISIBLE (-5125 3850);
FORCEPROP 2 LAST SEC_TYPE 0402
J 0
(-5125 3850);
DISPLAY 1.021277 (-5125 3850);
PAINT ORANGE (-5125 3850);
DISPLAY INVISIBLE (-5125 3850);
FORCEADD OFFPAGE..1
R 2
(-750 1525);
FORCEPROP 2 LAST $XR0 138 
J 0
(-564 1525);
DISPLAY 0.638298 (-564 1525);
PAINT MONO (-564 1525);
FORCEPROP 2 LAST $XR1 159 
J 0
(-444 1525);
DISPLAY 0.638298 (-444 1525);
PAINT MONO (-444 1525);
FORCEPROP 2 LAST $XR2 211 
J 0
(-324 1525);
DISPLAY 0.638298 (-324 1525);
PAINT MONO (-324 1525);
FORCEPROP 2 LAST $XR3 213 
J 0
(-564 1489);
DISPLAY 0.638298 (-564 1489);
PAINT MONO (-564 1489);
FORCEPROP 2 LAST $XR4 235 
J 0
(-444 1489);
DISPLAY 0.638298 (-444 1489);
PAINT MONO (-444 1489);
FORCEPROP 2 LAST $XR5 193 
J 0
(-324 1489);
DISPLAY 0.638298 (-324 1489);
PAINT MONO (-324 1489);
FORCEPROP 2 LAST $XR6 194 
J 0
(-564 1561);
DISPLAY 0.638298 (-564 1561);
PAINT MONO (-564 1561);
FORCEPROP 2 LAST $XR7 206 
J 0
(-444 1561);
DISPLAY 0.638298 (-444 1561);
PAINT MONO (-444 1561);
FORCEPROP 2 LAST $XR8 215 
J 0
(-324 1561);
DISPLAY 0.638298 (-324 1561);
PAINT MONO (-324 1561);
FORCEPROP 2 LAST $XR9 218 
J 0
(-564 1453);
DISPLAY 0.638298 (-564 1453);
PAINT MONO (-564 1453);
FORCEPROP 2 LAST $XR10 223 
J 0
(-444 1453);
DISPLAY 0.638298 (-444 1453);
PAINT MONO (-444 1453);
FORCEPROP 2 LAST $XR11 226 
J 0
(-324 1453);
DISPLAY 0.638298 (-324 1453);
PAINT MONO (-324 1453);
FORCEPROP 1 LAST COMMENT_BODY TRUE
J 2
(-875 1425);
DISPLAY 1.170213 (-875 1425);
PAINT GREEN (-875 1425);
DISPLAY INVISIBLE (-875 1425);
FORCEPROP 1 LAST OFFPAGE TRUE
J 2
(-1075 1400);
DISPLAY 1.170213 (-1075 1400);
PAINT GREEN (-1075 1400);
DISPLAY INVISIBLE (-1075 1400);
FORCEPROP 2 LAST ROOM PVCCIN_CPU0_VR
J 0
(-1175 1600);
DISPLAY 1.361702 (-1175 1600);
PAINT ORANGE (-1175 1600);
DISPLAY INVISIBLE (-1175 1600);
FORCEPROP 2 LAST CDS_LIB mstr_standard
J 0
(-750 1525);
PAINT ORANGE (-750 1525);
DISPLAY INVISIBLE (-750 1525);
FORCEPROP 2 LAST PATH I15
J 0
(-575 1600);
DISPLAY 1.021277 (-575 1600);
PAINT ORANGE (-575 1600);
DISPLAY INVISIBLE (-575 1600);
FORCEADD RES..2
(-6850 3625);
FORCEPROP 1 LAST MATERIAL CHIP
J 0
(-6810 3550);
DISPLAY 0.617021 (-6810 3550);
PAINT SKYBLUE (-6810 3550);
FORCEPROP 1 LASTPIN (-6850 3525) $PN 2
J 0
(-6845 3535);
DISPLAY 0.617021 (-6845 3535);
PAINT ORANGE (-6845 3535);
FORCEPROP 1 LAST PACK_TYPE 0402
J 0
(-7010 3675);
DISPLAY 0.617021 (-7010 3675);
PAINT SKYBLUE (-7010 3675);
FORCEPROP 1 LAST PART_NUMBER G21497-005
J 0
(-7060 3625);
DISPLAY 0.617021 (-7060 3625);
PAINT BLUE (-7060 3625);
FORCEPROP 1 LASTPIN (-6850 3725) $PN 1
J 0
(-6845 3687);
DISPLAY 0.617021 (-6845 3687);
PAINT ORANGE (-6845 3687);
FORCEPROP 1 LAST VALUE 0.0
J 0
(-6805 3700);
DISPLAY 0.617021 (-6805 3700);
PAINT SKYBLUE (-6805 3700);
FORCEPROP 1 LAST TOLERANCE 5%
J 0
(-6805 3650);
DISPLAY 0.617021 (-6805 3650);
PAINT SKYBLUE (-6805 3650);
FORCEPROP 1 LAST WATTAGE 1/16W
J 0
(-6810 3600);
DISPLAY 0.617021 (-6810 3600);
PAINT SKYBLUE (-6810 3600);
FORCEPROP 1 LAST LOCATION R6P43
J 0
(-6805 3750);
DISPLAY 0.617021 (-6805 3750);
PAINT AQUA (-6805 3750);
FORCEPROP 2 LAST CDS_LIB mstr_discrete
J 0
(-6850 3625);
PAINT ORANGE (-6850 3625);
DISPLAY INVISIBLE (-6850 3625);
FORCEPROP 2 LAST ROOM PVCCIN_CPU0_VR
J 0
(-6900 3725);
DISPLAY 1.361702 (-6900 3725);
PAINT ORANGE (-6900 3725);
DISPLAY INVISIBLE (-6900 3725);
FORCEPROP 2 LAST CDS_LOCATION R6P43
J 0
(-6805 3750);
DISPLAY 0.617021 (-6805 3750);
PAINT AQUA (-6805 3750);
DISPLAY INVISIBLE (-6805 3750);
FORCEPROP 1 LAST PATH I150
J 0
(-6800 3800);
DISPLAY 0.978723 (-6800 3800);
PAINT WHITE (-6800 3800);
DISPLAY INVISIBLE (-6800 3800);
FORCEPROP 2 LAST SEC_TYPE 0402
J 0
(-6800 3850);
DISPLAY 1.021277 (-6800 3850);
PAINT ORANGE (-6800 3850);
DISPLAY INVISIBLE (-6800 3850);
FORCEPROP 2 LAST SEC 1
J 0
(-6800 3850);
PAINT MONO (-6800 3850);
DISPLAY INVISIBLE (-6800 3850);
FORCEADD OFFPAGE..1
(-7675 1350);
FORCEPROP 2 LAST $XR0 201 
J 0
(-7927 1350);
DISPLAY 0.638298 (-7927 1350);
PAINT MONO (-7927 1350);
FORCEPROP 1 LAST COMMENT_BODY TRUE
J 0
(-7550 1250);
DISPLAY 1.170213 (-7550 1250);
PAINT GREEN (-7550 1250);
DISPLAY INVISIBLE (-7550 1250);
FORCEPROP 1 LAST OFFPAGE TRUE
J 0
(-7350 1225);
DISPLAY 1.170213 (-7350 1225);
PAINT GREEN (-7350 1225);
DISPLAY INVISIBLE (-7350 1225);
FORCEPROP 2 LAST ROOM PVCCIN_CPU0_VR
J 0
(-8225 1425);
DISPLAY 1.361702 (-8225 1425);
PAINT ORANGE (-8225 1425);
DISPLAY INVISIBLE (-8225 1425);
FORCEPROP 2 LAST PATH I152
J 0
(-7625 1425);
DISPLAY 1.021277 (-7625 1425);
PAINT ORANGE (-7625 1425);
DISPLAY INVISIBLE (-7625 1425);
FORCEPROP 2 LAST CDS_LIB mstr_standard
J 0
(-7675 1350);
PAINT ORANGE (-7675 1350);
DISPLAY INVISIBLE (-7675 1350);
FORCEADD RES..1
(-6375 1350);
FORCEPROP 1 LASTPIN (-6475 1350) $PN 1
J 0
(-6463 1362);
DISPLAY 0.617021 (-6463 1362);
PAINT ORANGE (-6463 1362);
FORCEPROP 1 LAST VALUE 0.0
J 2
(-6475 1250);
DISPLAY 0.617021 (-6475 1250);
PAINT SKYBLUE (-6475 1250);
FORCEPROP 1 LAST WATTAGE 1/16W
J 2
(-6400 1200);
DISPLAY 0.617021 (-6400 1200);
PAINT SKYBLUE (-6400 1200);
FORCEPROP 1 LAST TOLERANCE 5%
J 0
(-6425 1250);
DISPLAY 0.617021 (-6425 1250);
PAINT SKYBLUE (-6425 1250);
FORCEPROP 1 LAST PART_NUMBER G21497-005
J 0
(-6525 1300);
DISPLAY 0.617021 (-6525 1300);
PAINT BLUE (-6525 1300);
FORCEPROP 1 LAST LOCATION R6P29
J 0
(-6425 1400);
DISPLAY 0.617021 (-6425 1400);
PAINT AQUA (-6425 1400);
FORCEPROP 1 LAST PACK_TYPE 0402
J 0
(-6300 1250);
DISPLAY 0.617021 (-6300 1250);
PAINT SKYBLUE (-6300 1250);
FORCEPROP 1 LAST MATERIAL CHIP
J 0
(-6375 1200);
DISPLAY 0.617021 (-6375 1200);
PAINT SKYBLUE (-6375 1200);
FORCEPROP 1 LASTPIN (-6275 1350) $PN 2
J 0
(-6313 1362);
DISPLAY 0.617021 (-6313 1362);
PAINT ORANGE (-6313 1362);
FORCEPROP 2 LAST CDS_LOCATION R6P29
J 0
(-6425 1400);
DISPLAY 0.617021 (-6425 1400);
PAINT AQUA (-6425 1400);
DISPLAY INVISIBLE (-6425 1400);
FORCEPROP 2 LAST ROOM PVCCIN_CPU0_VR
J 0
(-6425 1450);
DISPLAY 1.361702 (-6425 1450);
PAINT ORANGE (-6425 1450);
DISPLAY INVISIBLE (-6425 1450);
FORCEPROP 2 LAST CDS_LIB mstr_discrete
J 0
(-6375 1350);
PAINT ORANGE (-6375 1350);
DISPLAY INVISIBLE (-6375 1350);
FORCEPROP 1 LAST PATH I154
J 0
(-6425 1500);
DISPLAY 0.978723 (-6425 1500);
PAINT WHITE (-6425 1500);
DISPLAY INVISIBLE (-6425 1500);
FORCEPROP 2 LAST SEC_TYPE 0402
J 0
(-6425 1550);
DISPLAY 1.021277 (-6425 1550);
PAINT ORANGE (-6425 1550);
DISPLAY INVISIBLE (-6425 1550);
FORCEPROP 2 LAST SEC 1
J 0
(-6425 1550);
DISPLAY 0.680851 (-6425 1550);
PAINT MONO (-6425 1550);
DISPLAY INVISIBLE (-6425 1550);
FORCEADD PXE1610B..1
(-3800 2575);
FORCEPROP 2 LASTPIN (-4250 1725) $PN 41
J 2
(-4260 1735);
DISPLAY 0.617021 (-4260 1735);
PAINT MONO (-4260 1735);
FORCEPROP 2 LASTPIN (-4250 1775) $PN 44
J 2
(-4260 1785);
DISPLAY 0.617021 (-4260 1785);
PAINT MONO (-4260 1785);
FORCEPROP 2 LASTPIN (-4250 1825) $PN 38
J 2
(-4260 1835);
DISPLAY 0.617021 (-4260 1835);
PAINT MONO (-4260 1835);
FORCEPROP 2 LASTPIN (-4250 1925) $PN 42
J 2
(-4260 1935);
DISPLAY 0.617021 (-4260 1935);
PAINT MONO (-4260 1935);
FORCEPROP 2 LASTPIN (-4250 1875) $PN 37
J 2
(-4260 1885);
DISPLAY 0.617021 (-4260 1885);
PAINT MONO (-4260 1885);
FORCEPROP 2 LASTPIN (-4250 2025) $PN 10
J 2
(-4260 2035);
DISPLAY 0.617021 (-4260 2035);
PAINT MONO (-4260 2035);
FORCEPROP 2 LASTPIN (-4250 2225) $PN 12
J 2
(-4260 2235);
DISPLAY 0.617021 (-4260 2235);
PAINT MONO (-4260 2235);
FORCEPROP 2 LASTPIN (-4250 2125) $PN 46
J 2
(-4260 2135);
DISPLAY 0.617021 (-4260 2135);
PAINT MONO (-4260 2135);
FORCEPROP 2 LASTPIN (-4250 2175) $PN 45
J 2
(-4260 2185);
DISPLAY 0.617021 (-4260 2185);
PAINT MONO (-4260 2185);
FORCEPROP 2 LASTPIN (-4250 2275) $PN 43
J 2
(-4260 2285);
DISPLAY 0.617021 (-4260 2285);
PAINT MONO (-4260 2285);
FORCEPROP 2 LASTPIN (-4250 2475) $PN 22
J 2
(-4260 2485);
DISPLAY 0.617021 (-4260 2485);
PAINT MONO (-4260 2485);
FORCEPROP 2 LASTPIN (-4250 2375) $PN 36
J 2
(-4260 2385);
DISPLAY 0.617021 (-4260 2385);
PAINT MONO (-4260 2385);
FORCEPROP 2 LASTPIN (-4250 2425) $PN 35
J 2
(-4260 2435);
DISPLAY 0.617021 (-4260 2435);
PAINT MONO (-4260 2435);
FORCEPROP 2 LASTPIN (-4250 2525) $PN 21
J 2
(-4260 2535);
DISPLAY 0.617021 (-4260 2535);
PAINT MONO (-4260 2535);
FORCEPROP 2 LASTPIN (-4250 2775) $PN 28
J 2
(-4260 2785);
DISPLAY 0.617021 (-4260 2785);
PAINT MONO (-4260 2785);
FORCEPROP 2 LASTPIN (-4250 2725) $PN 30
J 2
(-4260 2735);
DISPLAY 0.617021 (-4260 2735);
PAINT MONO (-4260 2735);
FORCEPROP 2 LASTPIN (-4250 2675) $PN 32
J 2
(-4260 2685);
DISPLAY 0.617021 (-4260 2685);
PAINT MONO (-4260 2685);
FORCEPROP 2 LASTPIN (-4250 2625) $PN 34
J 2
(-4260 2635);
DISPLAY 0.617021 (-4260 2635);
PAINT MONO (-4260 2635);
FORCEPROP 2 LASTPIN (-4250 2825) $PN 26
J 2
(-4260 2835);
DISPLAY 0.617021 (-4260 2835);
PAINT MONO (-4260 2835);
FORCEPROP 2 LASTPIN (-4250 2875) $PN 24
J 2
(-4260 2885);
DISPLAY 0.617021 (-4260 2885);
PAINT MONO (-4260 2885);
FORCEPROP 2 LASTPIN (-4250 2925) $PN 33
J 2
(-4260 2935);
DISPLAY 0.617021 (-4260 2935);
PAINT MONO (-4260 2935);
FORCEPROP 2 LASTPIN (-4250 2975) $PN 31
J 2
(-4260 2985);
DISPLAY 0.617021 (-4260 2985);
PAINT MONO (-4260 2985);
FORCEPROP 2 LASTPIN (-4250 3025) $PN 29
J 2
(-4260 3035);
DISPLAY 0.617021 (-4260 3035);
PAINT MONO (-4260 3035);
FORCEPROP 2 LASTPIN (-4250 3275) $PN 17
J 2
(-4260 3285);
DISPLAY 0.617021 (-4260 3285);
PAINT MONO (-4260 3285);
FORCEPROP 2 LASTPIN (-4250 3075) $PN 27
J 2
(-4260 3085);
DISPLAY 0.617021 (-4260 3085);
PAINT MONO (-4260 3085);
FORCEPROP 2 LASTPIN (-4250 3125) $PN 25
J 2
(-4260 3135);
DISPLAY 0.617021 (-4260 3135);
PAINT MONO (-4260 3135);
FORCEPROP 2 LASTPIN (-4250 3175) $PN 23
J 2
(-4260 3185);
DISPLAY 0.617021 (-4260 3185);
PAINT MONO (-4260 3185);
FORCEPROP 2 LASTPIN (-4250 3375) $PN 47
J 2
(-4260 3385);
DISPLAY 0.617021 (-4260 3385);
PAINT MONO (-4260 3385);
FORCEPROP 1 LAST MATERIAL IC
J 0
(-4200 3500);
DISPLAY 0.617021 (-4200 3500);
PAINT SKYBLUE (-4200 3500);
FORCEPROP 1 LAST PART_NUMBER H79206-001
J 0
(-4200 1625);
DISPLAY 0.617021 (-4200 1625);
PAINT BLUE (-4200 1625);
FORCEPROP 1 LAST LOCATION EU4D4
J 0
(-4200 3550);
DISPLAY 0.617021 (-4200 3550);
PAINT AQUA (-4200 3550);
FORCEPROP 2 LASTPIN (-3350 1825) $PN 49
J 0
(-3340 1835);
DISPLAY 0.617021 (-3340 1835);
PAINT MONO (-3340 1835);
FORCEPROP 2 LASTPIN (-3350 2025) $PN 9
J 0
(-3340 2035);
DISPLAY 0.617021 (-3340 2035);
PAINT MONO (-3340 2035);
FORCEPROP 2 LASTPIN (-3350 2475) $PN 7
J 0
(-3340 2485);
DISPLAY 0.617021 (-3340 2485);
PAINT MONO (-3340 2485);
FORCEPROP 2 LASTPIN (-3350 2425) $PN 6
J 0
(-3340 2435);
DISPLAY 0.617021 (-3340 2435);
PAINT MONO (-3340 2435);
FORCEPROP 2 LASTPIN (-3350 2375) $PN 5
J 0
(-3340 2385);
DISPLAY 0.617021 (-3340 2385);
PAINT MONO (-3340 2385);
FORCEPROP 2 LASTPIN (-3350 2325) $PN 4
J 0
(-3340 2335);
DISPLAY 0.617021 (-3340 2335);
PAINT MONO (-3340 2335);
FORCEPROP 2 LASTPIN (-3350 2275) $PN 3
J 0
(-3340 2285);
DISPLAY 0.617021 (-3340 2285);
PAINT MONO (-3340 2285);
FORCEPROP 2 LASTPIN (-3350 2225) $PN 2
J 0
(-3340 2235);
DISPLAY 0.617021 (-3340 2235);
PAINT MONO (-3340 2235);
FORCEPROP 2 LASTPIN (-3350 2125) $PN 8
J 0
(-3340 2135);
DISPLAY 0.617021 (-3340 2135);
PAINT MONO (-3340 2135);
FORCEPROP 2 LASTPIN (-3350 2525) $PN 1
J 0
(-3340 2535);
DISPLAY 0.617021 (-3340 2535);
PAINT MONO (-3340 2535);
FORCEPROP 2 LASTPIN (-3350 2675) $PN 15
J 0
(-3340 2685);
DISPLAY 0.617021 (-3340 2685);
PAINT MONO (-3340 2685);
FORCEPROP 2 LASTPIN (-3350 2625) $PN 16
J 0
(-3340 2635);
DISPLAY 0.617021 (-3340 2635);
PAINT MONO (-3340 2635);
FORCEPROP 2 LASTPIN (-3350 2875) $PN 19
J 0
(-3340 2885);
DISPLAY 0.617021 (-3340 2885);
PAINT MONO (-3340 2885);
FORCEPROP 2 LASTPIN (-3350 2775) $PN 48
J 0
(-3340 2785);
DISPLAY 0.617021 (-3340 2785);
PAINT MONO (-3340 2785);
FORCEPROP 2 LASTPIN (-3350 2725) $PN 18
J 0
(-3340 2735);
DISPLAY 0.617021 (-3340 2735);
PAINT MONO (-3340 2735);
FORCEPROP 2 LASTPIN (-3350 2975) $PN 13
J 0
(-3340 2985);
DISPLAY 0.617021 (-3340 2985);
PAINT MONO (-3340 2985);
FORCEPROP 2 LASTPIN (-3350 3325) $PN 11
J 0
(-3340 3335);
DISPLAY 0.617021 (-3340 3335);
PAINT MONO (-3340 3335);
FORCEPROP 2 LASTPIN (-3350 3275) $PN 20
J 0
(-3340 3285);
DISPLAY 0.617021 (-3340 3285);
PAINT MONO (-3340 3285);
FORCEPROP 2 LASTPIN (-3350 3125) $PN 39
J 0
(-3340 3135);
DISPLAY 0.617021 (-3340 3135);
PAINT MONO (-3340 3135);
FORCEPROP 2 LASTPIN (-3350 3075) $PN 40
J 0
(-3340 3085);
DISPLAY 0.617021 (-3340 3085);
PAINT MONO (-3340 3085);
FORCEPROP 2 LASTPIN (-3350 3225) $PN 14
J 0
(-3340 3235);
DISPLAY 0.617021 (-3340 3235);
PAINT MONO (-3340 3235);
FORCEPROP 2 LAST CDS_LOCATION EU4D4
J 0
(-4200 3550);
DISPLAY 0.617021 (-4200 3550);
PAINT AQUA (-4200 3550);
DISPLAY INVISIBLE (-4200 3550);
FORCEPROP 1 LAST PACK_TYPE QFN
J 0
(-4200 3600);
PAINT SKYBLUE (-4200 3600);
DISPLAY INVISIBLE (-4200 3600);
FORCEPROP 2 LAST CDS_SEC 1
J 0
(-4200 3600);
PAINT MONO (-4200 3600);
DISPLAY INVISIBLE (-4200 3600);
FORCEPROP 2 LAST $SEC 1
J 0
(-4200 3600);
PAINT MONO (-4200 3600);
DISPLAY INVISIBLE (-4200 3600);
FORCEPROP 2 LAST CDS_LIB mstr_controller
J 0
(-3800 2575);
PAINT ORANGE (-3800 2575);
DISPLAY INVISIBLE (-3800 2575);
FORCEPROP 1 LAST CDS_LMAN_SYM_OUTLINE -400,900,400,-900
J 0
(-3800 2575);
DISPLAY 0.468085 (-3800 2575);
PAINT GREEN (-3800 2575);
DISPLAY INVISIBLE (-3800 2575);
FORCEPROP 1 LAST PATH I155
J 0
(-3700 3501);
PAINT WHITE (-3700 3501);
DISPLAY INVISIBLE (-3700 3501);
FORCEADD OFFPAGE..1
R 2
(-1075 1175);
FORCEPROP 2 LAST $XR0 201 
J 0
(-889 1175);
DISPLAY 0.638298 (-889 1175);
PAINT MONO (-889 1175);
FORCEPROP 1 LAST COMMENT_BODY TRUE
J 2
(-1200 1075);
DISPLAY 1.170213 (-1200 1075);
PAINT GREEN (-1200 1075);
DISPLAY INVISIBLE (-1200 1075);
FORCEPROP 1 LAST OFFPAGE TRUE
J 2
(-1400 1050);
DISPLAY 1.170213 (-1400 1050);
PAINT GREEN (-1400 1050);
DISPLAY INVISIBLE (-1400 1050);
FORCEPROP 2 LAST ROOM PVCCIN_CPU0_VR
J 0
(-1500 1250);
DISPLAY 1.361702 (-1500 1250);
PAINT ORANGE (-1500 1250);
DISPLAY INVISIBLE (-1500 1250);
FORCEPROP 2 LAST CDS_LIB mstr_standard
J 2
(-1075 1175);
PAINT ORANGE (-1075 1175);
DISPLAY INVISIBLE (-1075 1175);
FORCEPROP 2 LAST PATH I17
J 0
(-900 1250);
DISPLAY 1.021277 (-900 1250);
PAINT ORANGE (-900 1250);
DISPLAY INVISIBLE (-900 1250);
FORCEADD PVCCIO_CPU0..1
(-1275 3950);
FORCEPROP 3 LASTPIN (-1275 3900) SIG_NAME PVCCIO_CPU0\g
J 0
(-1265 3910);
DISPLAY 0.659574 (-1265 3910);
PAINT MONO (-1265 3910);
DISPLAY INVISIBLE (-1265 3910);
FORCEPROP 1 LAST HDL_POWER PVCCIO_CPU0
J 1
(-1275 4000);
DISPLAY 0.872340 (-1275 4000);
PAINT GREEN (-1275 4000);
DISPLAY INVISIBLE (-1275 4000);
FORCEPROP 1 LAST BODY_TYPE PLUMBING
J 0
(-1320 3907);
DISPLAY 0.340426 (-1320 3907);
PAINT GREEN (-1320 3907);
DISPLAY INVISIBLE (-1320 3907);
FORCEPROP 1 LAST VOLTAGE 1.1V
J 0
(-1320 3907);
DISPLAY 0.340426 (-1320 3907);
PAINT SKYBLUE (-1320 3907);
DISPLAY INVISIBLE (-1320 3907);
FORCEPROP 2 LAST CDS_LIB mstr_symbols
J 0
(-1275 3950);
PAINT ORANGE (-1275 3950);
DISPLAY INVISIBLE (-1275 3950);
FORCEPROP 1 LAST PATH I18
J 0
(-1225 3975);
DISPLAY 0.872340 (-1225 3975);
PAINT AQUA (-1225 3975);
DISPLAY INVISIBLE (-1225 3975);
FORCEADD RES..2
(-1925 4100);
FORCEPROP 1 LASTPIN (-1925 4000) $PN 2
J 0
(-1920 4010);
DISPLAY 0.617021 (-1920 4010);
PAINT ORANGE (-1920 4010);
FORCEPROP 1 LAST PACK_TYPE 0402
J 0
(-1885 3925);
DISPLAY 0.617021 (-1885 3925);
PAINT SKYBLUE (-1885 3925);
FORCEPROP 1 LAST PART_NUMBER G21796-311
J 0
(-1885 3975);
DISPLAY 0.617021 (-1885 3975);
PAINT BLUE (-1885 3975);
FORCEPROP 1 LAST WATTAGE 1/16W
J 0
(-1885 4075);
DISPLAY 0.617021 (-1885 4075);
PAINT SKYBLUE (-1885 4075);
FORCEPROP 1 LASTPIN (-1925 4200) $PN 1
J 0
(-1920 4162);
DISPLAY 0.617021 (-1920 4162);
PAINT ORANGE (-1920 4162);
FORCEPROP 1 LAST TOLERANCE 1.0%
J 0
(-1880 4125);
DISPLAY 0.617021 (-1880 4125);
PAINT SKYBLUE (-1880 4125);
FORCEPROP 1 LAST VALUE 2.26K
J 0
(-1880 4175);
DISPLAY 0.617021 (-1880 4175);
PAINT SKYBLUE (-1880 4175);
FORCEPROP 1 LAST LOCATION R4E4
J 0
(-1880 4225);
DISPLAY 0.617021 (-1880 4225);
PAINT AQUA (-1880 4225);
FORCEPROP 1 LAST MATERIAL CHIP
J 0
(-1885 4025);
PAINT SKYBLUE (-1885 4025);
DISPLAY INVISIBLE (-1885 4025);
FORCEPROP 2 LAST ROOM PVCCIN_CPU0_VR
J 0
(-1875 4075);
DISPLAY 1.361702 (-1875 4075);
PAINT ORANGE (-1875 4075);
DISPLAY INVISIBLE (-1875 4075);
FORCEPROP 2 LAST CDS_LIB mstr_discrete
J 0
(-1925 4100);
PAINT ORANGE (-1925 4100);
DISPLAY INVISIBLE (-1925 4100);
FORCEPROP 2 LAST CDS_LOCATION R4E4
J 0
(-1880 4225);
DISPLAY 0.617021 (-1880 4225);
PAINT AQUA (-1880 4225);
DISPLAY INVISIBLE (-1880 4225);
FORCEPROP 1 LAST PATH I19
J 0
(-1875 4275);
DISPLAY 0.978723 (-1875 4275);
PAINT WHITE (-1875 4275);
DISPLAY INVISIBLE (-1875 4275);
FORCEPROP 2 LAST SEC_TYPE 0402
J 0
(-1875 4325);
DISPLAY 1.021277 (-1875 4325);
PAINT ORANGE (-1875 4325);
DISPLAY INVISIBLE (-1875 4325);
FORCEPROP 2 LAST SEC 1
J 0
(-1875 4325);
DISPLAY 0.680851 (-1875 4325);
PAINT MONO (-1875 4325);
DISPLAY INVISIBLE (-1875 4325);
FORCEADD OFFPAGE..2
(-1050 2975);
FORCEPROP 2 LAST $XR0 95 
J 0
(-861 2975);
DISPLAY 0.638298 (-861 2975);
PAINT MONO (-861 2975);
FORCEPROP 2 LAST $XR1 120 
J 0
(-771 2975);
DISPLAY 0.638298 (-771 2975);
PAINT MONO (-771 2975);
FORCEPROP 2 LAST $XR2 145 
J 0
(-651 2975);
DISPLAY 0.638298 (-651 2975);
PAINT MONO (-651 2975);
FORCEPROP 1 LAST COMMENT_BODY TRUE
J 0
(-1095 2880);
DISPLAY 1.170213 (-1095 2880);
PAINT GREEN (-1095 2880);
DISPLAY INVISIBLE (-1095 2880);
FORCEPROP 1 LAST OFFPAGE TRUE
J 0
(-725 2850);
DISPLAY 1.170213 (-725 2850);
PAINT GREEN (-725 2850);
DISPLAY INVISIBLE (-725 2850);
FORCEPROP 2 LAST CDS_LIB mstr_standard
J 0
(-1050 2975);
PAINT ORANGE (-1050 2975);
DISPLAY INVISIBLE (-1050 2975);
FORCEPROP 2 LAST ROOM PVCCIN_CPU0_VR
J 0
(-1475 3050);
DISPLAY 1.361702 (-1475 3050);
PAINT ORANGE (-1475 3050);
DISPLAY INVISIBLE (-1475 3050);
FORCEPROP 2 LAST PATH I2
J 0
(-875 3050);
DISPLAY 1.021277 (-875 3050);
PAINT ORANGE (-875 3050);
DISPLAY INVISIBLE (-875 3050);
FORCEADD RES..2
(-1275 3750);
FORCEPROP 1 LAST PACK_TYPE 0402
J 0
(-1235 3575);
DISPLAY 0.617021 (-1235 3575);
PAINT SKYBLUE (-1235 3575);
FORCEPROP 1 LASTPIN (-1275 3850) $PN 1
J 0
(-1270 3812);
DISPLAY 0.617021 (-1270 3812);
PAINT ORANGE (-1270 3812);
FORCEPROP 1 LASTPIN (-1275 3650) $PN 2
J 0
(-1270 3660);
DISPLAY 0.617021 (-1270 3660);
PAINT ORANGE (-1270 3660);
FORCEPROP 1 LAST WATTAGE 1/16W
J 0
(-1235 3725);
DISPLAY 0.617021 (-1235 3725);
PAINT SKYBLUE (-1235 3725);
FORCEPROP 1 LAST MATERIAL CHIP
J 0
(-1235 3675);
DISPLAY 0.617021 (-1235 3675);
PAINT SKYBLUE (-1235 3675);
FORCEPROP 1 LAST TOLERANCE 1%
J 0
(-1230 3775);
DISPLAY 0.617021 (-1230 3775);
PAINT SKYBLUE (-1230 3775);
FORCEPROP 1 LAST VALUE 100.0
J 0
(-1230 3825);
DISPLAY 0.617021 (-1230 3825);
PAINT SKYBLUE (-1230 3825);
FORCEPROP 1 LAST LOCATION R4E10
J 0
(-1230 3875);
DISPLAY 0.617021 (-1230 3875);
PAINT AQUA (-1230 3875);
FORCEPROP 1 LAST PART_NUMBER G21796-017
J 0
(-1235 3625);
DISPLAY 0.617021 (-1235 3625);
PAINT BLUE (-1235 3625);
FORCEPROP 2 LAST CDS_LIB mstr_discrete
J 0
(-1275 3750);
PAINT ORANGE (-1275 3750);
DISPLAY INVISIBLE (-1275 3750);
FORCEPROP 2 LAST CDS_LOCATION R4E10
J 0
(-1230 3875);
DISPLAY 0.617021 (-1230 3875);
PAINT AQUA (-1230 3875);
DISPLAY INVISIBLE (-1230 3875);
FORCEPROP 1 LAST PATH I20
J 0
(-1225 3925);
DISPLAY 0.978723 (-1225 3925);
PAINT WHITE (-1225 3925);
DISPLAY INVISIBLE (-1225 3925);
FORCEPROP 2 LAST ROOM PVCCIN_CPU0_VR
J 0
(-1225 3925);
DISPLAY 1.361702 (-1225 3925);
PAINT ORANGE (-1225 3925);
DISPLAY INVISIBLE (-1225 3925);
FORCEPROP 2 LAST SEC_TYPE 0402
J 0
(-1225 3975);
DISPLAY 1.021277 (-1225 3975);
PAINT ORANGE (-1225 3975);
DISPLAY INVISIBLE (-1225 3975);
FORCEPROP 2 LAST SEC 1
J 0
(-1225 3975);
DISPLAY 0.680851 (-1225 3975);
PAINT MONO (-1225 3975);
DISPLAY INVISIBLE (-1225 3975);
FORCEADD RES..2
(-2075 3750);
FORCEPROP 1 LAST MATERIAL EMPTY
R 1
J 0
(-2185 3675);
DISPLAY 0.617021 (-2185 3675);
PAINT RED (-2185 3675);
FORCEPROP 1 LASTPIN (-2075 3850) $PN 1
J 0
(-2070 3812);
DISPLAY 0.617021 (-2070 3812);
PAINT ORANGE (-2070 3812);
FORCEPROP 1 LASTPIN (-2075 3650) $PN 2
J 0
(-2070 3660);
DISPLAY 0.617021 (-2070 3660);
PAINT ORANGE (-2070 3660);
FORCEPROP 1 LAST PACK_TYPE 0402
J 0
(-2035 3575);
DISPLAY 0.617021 (-2035 3575);
PAINT SKYBLUE (-2035 3575);
FORCEPROP 1 LAST TOLERANCE 1.0%
J 0
(-2030 3775);
DISPLAY 0.617021 (-2030 3775);
PAINT SKYBLUE (-2030 3775);
FORCEPROP 1 LAST VALUE 2.26K
J 0
(-2030 3825);
DISPLAY 0.617021 (-2030 3825);
PAINT SKYBLUE (-2030 3825);
FORCEPROP 1 LAST LOCATION R4D31
J 0
(-2030 3875);
DISPLAY 0.617021 (-2030 3875);
PAINT AQUA (-2030 3875);
FORCEPROP 1 LAST PART_NUMBER G21796-311
J 0
(-2035 3625);
DISPLAY 0.617021 (-2035 3625);
PAINT BLUE (-2035 3625);
FORCEPROP 2 LAST CDS_LIB mstr_discrete
J 0
(-2075 3750);
PAINT ORANGE (-2075 3750);
DISPLAY INVISIBLE (-2075 3750);
FORCEPROP 2 LAST ROOM PVCCIN_CPU0_VR
J 0
(-2025 3725);
DISPLAY 1.361702 (-2025 3725);
PAINT ORANGE (-2025 3725);
DISPLAY INVISIBLE (-2025 3725);
FORCEPROP 1 LAST WATTAGE 1/16W
J 0
(-2035 3725);
DISPLAY 0.914894 (-2035 3725);
PAINT SKYBLUE (-2035 3725);
DISPLAY INVISIBLE (-2035 3725);
FORCEPROP 1 LAST PATH I22
J 0
(-2025 3925);
DISPLAY 0.978723 (-2025 3925);
PAINT WHITE (-2025 3925);
DISPLAY INVISIBLE (-2025 3925);
FORCEPROP 2 LAST CDS_LOCATION R4D31
J 0
(-2030 3875);
DISPLAY 0.617021 (-2030 3875);
PAINT AQUA (-2030 3875);
DISPLAY INVISIBLE (-2030 3875);
FORCEPROP 2 LAST SEC 1
J 0
(-2025 3975);
DISPLAY 0.680851 (-2025 3975);
PAINT MONO (-2025 3975);
DISPLAY INVISIBLE (-2025 3975);
FORCEPROP 2 LAST SEC_TYPE 0402
J 0
(-2025 3975);
DISPLAY 1.021277 (-2025 3975);
PAINT ORANGE (-2025 3975);
DISPLAY INVISIBLE (-2025 3975);
FORCEADD RES..2
(-2500 3925);
FORCEPROP 1 LAST PACK_TYPE 0402
J 0
(-2460 3750);
DISPLAY 0.617021 (-2460 3750);
PAINT SKYBLUE (-2460 3750);
FORCEPROP 1 LASTPIN (-2500 3825) $PN 2
J 0
(-2495 3835);
DISPLAY 0.617021 (-2495 3835);
PAINT ORANGE (-2495 3835);
FORCEPROP 1 LASTPIN (-2500 4025) $PN 1
J 0
(-2495 3987);
DISPLAY 0.617021 (-2495 3987);
PAINT ORANGE (-2495 3987);
FORCEPROP 1 LAST LOCATION R4D58
J 0
(-2455 4050);
DISPLAY 0.617021 (-2455 4050);
PAINT AQUA (-2455 4050);
FORCEPROP 1 LAST VALUE 1.00K
J 0
(-2455 4000);
DISPLAY 0.617021 (-2455 4000);
PAINT SKYBLUE (-2455 4000);
FORCEPROP 1 LAST TOLERANCE 1%
J 0
(-2455 3950);
DISPLAY 0.617021 (-2455 3950);
PAINT SKYBLUE (-2455 3950);
FORCEPROP 1 LAST MATERIAL CHIP
J 0
(-2460 3850);
DISPLAY 0.617021 (-2460 3850);
PAINT SKYBLUE (-2460 3850);
FORCEPROP 1 LAST WATTAGE 1/16W
J 0
(-2460 3900);
DISPLAY 0.617021 (-2460 3900);
PAINT SKYBLUE (-2460 3900);
FORCEPROP 1 LAST PART_NUMBER G21796-026
J 0
(-2460 3800);
DISPLAY 0.617021 (-2460 3800);
PAINT BLUE (-2460 3800);
FORCEPROP 2 LAST CDS_LOCATION R4D58
J 0
(-2455 4050);
DISPLAY 0.617021 (-2455 4050);
PAINT AQUA (-2455 4050);
DISPLAY INVISIBLE (-2455 4050);
FORCEPROP 2 LAST CDS_LIB mstr_discrete
J 2
(-2500 3925);
PAINT ORANGE (-2500 3925);
DISPLAY INVISIBLE (-2500 3925);
FORCEPROP 2 LAST ROOM PVCCIN_CPU0_VR
J 0
(-2450 4100);
DISPLAY 1.361702 (-2450 4100);
PAINT ORANGE (-2450 4100);
DISPLAY INVISIBLE (-2450 4100);
FORCEPROP 1 LAST PATH I25
J 0
(-2450 4100);
DISPLAY 0.978723 (-2450 4100);
PAINT WHITE (-2450 4100);
DISPLAY INVISIBLE (-2450 4100);
FORCEPROP 2 LAST SEC 1
J 0
(-2450 4150);
DISPLAY 0.680851 (-2450 4150);
PAINT MONO (-2450 4150);
DISPLAY INVISIBLE (-2450 4150);
FORCEPROP 2 LAST SEC_TYPE 0402
J 0
(-2450 4150);
DISPLAY 1.021277 (-2450 4150);
PAINT ORANGE (-2450 4150);
DISPLAY INVISIBLE (-2450 4150);
FORCEADD RES..1
(-2025 2875);
FORCEPROP 1 LASTPIN (-2125 2875) $PN 1
J 0
(-2113 2887);
DISPLAY 0.617021 (-2113 2887);
PAINT ORANGE (-2113 2887);
FORCEPROP 1 LAST WATTAGE 1/16W
J 2
(-2050 2675);
DISPLAY 0.617021 (-2050 2675);
PAINT SKYBLUE (-2050 2675);
FORCEPROP 1 LAST VALUE 0.0
J 2
(-2150 2725);
DISPLAY 0.617021 (-2150 2725);
PAINT SKYBLUE (-2150 2725);
FORCEPROP 1 LAST TOLERANCE 5%
J 0
(-2100 2725);
DISPLAY 0.617021 (-2100 2725);
PAINT SKYBLUE (-2100 2725);
FORCEPROP 1 LAST PART_NUMBER G21497-005
J 0
(-2175 2775);
DISPLAY 0.617021 (-2175 2775);
PAINT BLUE (-2175 2775);
FORCEPROP 1 LAST LOCATION R4D67
J 0
(-2075 2925);
DISPLAY 0.617021 (-2075 2925);
PAINT AQUA (-2075 2925);
FORCEPROP 1 LAST MATERIAL CHIP
J 0
(-2000 2675);
DISPLAY 0.617021 (-2000 2675);
PAINT SKYBLUE (-2000 2675);
FORCEPROP 1 LAST PACK_TYPE 0402
J 0
(-2000 2725);
DISPLAY 0.617021 (-2000 2725);
PAINT SKYBLUE (-2000 2725);
FORCEPROP 1 LASTPIN (-1925 2875) $PN 2
J 0
(-1963 2887);
DISPLAY 0.617021 (-1963 2887);
PAINT ORANGE (-1963 2887);
FORCEPROP 2 LAST ROOM PVCCIN_CPU0_VR
J 0
(-2075 2975);
DISPLAY 1.361702 (-2075 2975);
PAINT ORANGE (-2075 2975);
DISPLAY INVISIBLE (-2075 2975);
FORCEPROP 1 LAST PATH I26
J 0
(-2075 3025);
DISPLAY 0.978723 (-2075 3025);
PAINT WHITE (-2075 3025);
DISPLAY INVISIBLE (-2075 3025);
FORCEPROP 2 LAST CDS_LOCATION R4D67
J 0
(-2075 2925);
DISPLAY 0.617021 (-2075 2925);
PAINT AQUA (-2075 2925);
DISPLAY INVISIBLE (-2075 2925);
FORCEPROP 2 LAST SEC 1
J 0
(-2075 3075);
DISPLAY 0.680851 (-2075 3075);
PAINT MONO (-2075 3075);
DISPLAY INVISIBLE (-2075 3075);
FORCEPROP 2 LAST SEC_TYPE 0402
J 0
(-2075 3075);
DISPLAY 1.021277 (-2075 3075);
PAINT ORANGE (-2075 3075);
DISPLAY INVISIBLE (-2075 3075);
FORCEPROP 2 LAST CDS_LIB mstr_discrete
J 0
(-2025 2875);
PAINT ORANGE (-2025 2875);
DISPLAY INVISIBLE (-2025 2875);
FORCEADD RES..2
R 2
(-2775 3925);
FORCEPROP 1 LAST PART_NUMBER G21796-026
J 2
(-2815 3800);
DISPLAY 0.617021 (-2815 3800);
PAINT BLUE (-2815 3800);
FORCEPROP 1 LAST VALUE 1.00K
J 2
(-2820 4000);
DISPLAY 0.617021 (-2820 4000);
PAINT SKYBLUE (-2820 4000);
FORCEPROP 1 LAST LOCATION R4E5
J 2
(-2820 4050);
DISPLAY 0.617021 (-2820 4050);
PAINT AQUA (-2820 4050);
FORCEPROP 1 LAST TOLERANCE 1%
J 2
(-2820 3950);
DISPLAY 0.617021 (-2820 3950);
PAINT SKYBLUE (-2820 3950);
FORCEPROP 1 LAST WATTAGE 1/16W
J 2
(-2815 3900);
DISPLAY 0.617021 (-2815 3900);
PAINT SKYBLUE (-2815 3900);
FORCEPROP 1 LAST MATERIAL CHIP
J 2
(-2815 3850);
DISPLAY 0.617021 (-2815 3850);
PAINT SKYBLUE (-2815 3850);
FORCEPROP 1 LAST PACK_TYPE 0402
J 2
(-2815 3750);
DISPLAY 0.617021 (-2815 3750);
PAINT SKYBLUE (-2815 3750);
FORCEPROP 1 LASTPIN (-2775 3825) $PN 2
J 2
(-2780 3835);
DISPLAY 0.617021 (-2780 3835);
PAINT ORANGE (-2780 3835);
FORCEPROP 1 LASTPIN (-2775 4025) $PN 1
J 2
(-2780 3987);
DISPLAY 0.617021 (-2780 3987);
PAINT ORANGE (-2780 3987);
FORCEPROP 2 LAST CDS_LOCATION R4E5
J 2
(-2820 4050);
DISPLAY 0.617021 (-2820 4050);
PAINT AQUA (-2820 4050);
DISPLAY INVISIBLE (-2820 4050);
FORCEPROP 2 LAST CDS_LIB mstr_discrete
J 2
(-2775 3925);
PAINT ORANGE (-2775 3925);
DISPLAY INVISIBLE (-2775 3925);
FORCEPROP 2 LAST SEC_TYPE 0402
J 0
(-2825 4150);
DISPLAY 1.021277 (-2825 4150);
PAINT ORANGE (-2825 4150);
DISPLAY INVISIBLE (-2825 4150);
FORCEPROP 2 LAST SEC 1
J 0
(-2825 4150);
DISPLAY 0.680851 (-2825 4150);
PAINT MONO (-2825 4150);
DISPLAY INVISIBLE (-2825 4150);
FORCEPROP 1 LAST PATH I27
J 2
(-2825 4100);
DISPLAY 0.978723 (-2825 4100);
PAINT WHITE (-2825 4100);
DISPLAY INVISIBLE (-2825 4100);
FORCEPROP 2 LAST ROOM PVCCIN_CPU0_VR
J 0
(-2800 4100);
DISPLAY 1.361702 (-2800 4100);
PAINT ORANGE (-2800 4100);
DISPLAY INVISIBLE (-2800 4100);
FORCEADD RES..1
(-1900 1775);
FORCEPROP 1 LAST WATTAGE 1/16W
J 2
(-1925 1625);
DISPLAY 0.617021 (-1925 1625);
PAINT SKYBLUE (-1925 1625);
FORCEPROP 1 LAST VALUE 0.0
J 2
(-2000 1675);
DISPLAY 0.617021 (-2000 1675);
PAINT SKYBLUE (-2000 1675);
FORCEPROP 1 LAST PART_NUMBER G21497-005
J 0
(-2050 1725);
DISPLAY 0.617021 (-2050 1725);
PAINT BLUE (-2050 1725);
FORCEPROP 1 LAST TOLERANCE 5%
J 0
(-1950 1675);
DISPLAY 0.617021 (-1950 1675);
PAINT SKYBLUE (-1950 1675);
FORCEPROP 1 LASTPIN (-2000 1775) $PN 1
J 0
(-1988 1787);
DISPLAY 0.617021 (-1988 1787);
PAINT ORANGE (-1988 1787);
FORCEPROP 1 LASTPIN (-1800 1775) $PN 2
J 0
(-1838 1787);
DISPLAY 0.617021 (-1838 1787);
PAINT ORANGE (-1838 1787);
FORCEPROP 1 LAST LOCATION R4D50
J 0
(-1950 1825);
DISPLAY 0.617021 (-1950 1825);
PAINT AQUA (-1950 1825);
FORCEPROP 1 LAST MATERIAL CHIP
J 0
(-1900 1625);
DISPLAY 0.617021 (-1900 1625);
PAINT SKYBLUE (-1900 1625);
FORCEPROP 1 LAST PACK_TYPE 0402
J 0
(-1825 1675);
DISPLAY 0.617021 (-1825 1675);
PAINT SKYBLUE (-1825 1675);
FORCEPROP 2 LAST CDS_LIB mstr_discrete
J 0
(-1900 1775);
PAINT ORANGE (-1900 1775);
DISPLAY INVISIBLE (-1900 1775);
FORCEPROP 2 LAST ROOM PVCCIN_CPU0_VR
J 0
(-1950 1875);
DISPLAY 1.361702 (-1950 1875);
PAINT ORANGE (-1950 1875);
DISPLAY INVISIBLE (-1950 1875);
FORCEPROP 1 LAST PATH I28
J 0
(-1950 1925);
DISPLAY 0.978723 (-1950 1925);
PAINT WHITE (-1950 1925);
DISPLAY INVISIBLE (-1950 1925);
FORCEPROP 2 LAST CDS_LOCATION R4D50
J 0
(-1950 1825);
DISPLAY 0.617021 (-1950 1825);
PAINT AQUA (-1950 1825);
DISPLAY INVISIBLE (-1950 1825);
FORCEPROP 2 LAST SEC 1
J 0
(-1950 1975);
DISPLAY 0.680851 (-1950 1975);
PAINT MONO (-1950 1975);
DISPLAY INVISIBLE (-1950 1975);
FORCEPROP 2 LAST SEC_TYPE 0402
J 0
(-1950 1975);
DISPLAY 1.021277 (-1950 1975);
PAINT ORANGE (-1950 1975);
DISPLAY INVISIBLE (-1950 1975);
FORCEADD GND..1
(-1475 675);
FORCEPROP 3 LASTPIN (-1475 725) SIG_NAME GND\g
J 0
(-1465 735);
DISPLAY 0.659574 (-1465 735);
PAINT MONO (-1465 735);
DISPLAY INVISIBLE (-1465 735);
FORCEPROP 1 LAST HDL_POWER GND
J 0
(-1475 825);
DISPLAY 1.170213 (-1475 825);
PAINT GREEN (-1475 825);
DISPLAY INVISIBLE (-1475 825);
FORCEPROP 1 LAST BODY_TYPE PLUMBING
J 0
(-1520 632);
DISPLAY 0.340426 (-1520 632);
PAINT GREEN (-1520 632);
DISPLAY INVISIBLE (-1520 632);
FORCEPROP 2 LAST ROOM PVCCIN_CPU0_VR
J 0
(-2050 750);
DISPLAY 1.361702 (-2050 750);
PAINT ORANGE (-2050 750);
DISPLAY INVISIBLE (-2050 750);
FORCEPROP 1 LAST PATH I29
J 0
(-1400 675);
DISPLAY 0.872340 (-1400 675);
PAINT AQUA (-1400 675);
DISPLAY INVISIBLE (-1400 675);
FORCEPROP 2 LAST CDS_LIB mstr_symbols
J 0
(-1475 675);
PAINT ORANGE (-1475 675);
DISPLAY INVISIBLE (-1475 675);
FORCEPROP 1 LAST SIZE 1B
J 0
(-1400 625);
DISPLAY 1.170213 (-1400 625);
PAINT AQUA (-1400 625);
DISPLAY INVISIBLE (-1400 625);
FORCEPROP 1 LAST VOLTAGE 0
J 0
(-1475 675);
PAINT SKYBLUE (-1475 675);
DISPLAY INVISIBLE (-1475 675);
FORCEADD OFFPAGE..2
(-1050 2875);
FORCEPROP 2 LAST $XR0 194 
J 0
(-861 2875);
DISPLAY 0.638298 (-861 2875);
PAINT MONO (-861 2875);
FORCEPROP 2 LAST $XR1 211 
J 0
(-741 2875);
DISPLAY 0.638298 (-741 2875);
PAINT MONO (-741 2875);
FORCEPROP 2 LAST $XR2 21 
J 0
(-621 2875);
DISPLAY 0.638298 (-621 2875);
PAINT MONO (-621 2875);
FORCEPROP 1 LAST COMMENT_BODY TRUE
J 0
(-1095 2780);
DISPLAY 1.170213 (-1095 2780);
PAINT GREEN (-1095 2780);
DISPLAY INVISIBLE (-1095 2780);
FORCEPROP 1 LAST OFFPAGE TRUE
J 0
(-725 2750);
DISPLAY 1.170213 (-725 2750);
PAINT GREEN (-725 2750);
DISPLAY INVISIBLE (-725 2750);
FORCEPROP 2 LAST ROOM PVCCIN_CPU0_VR
J 0
(-1475 2950);
DISPLAY 1.361702 (-1475 2950);
PAINT ORANGE (-1475 2950);
DISPLAY INVISIBLE (-1475 2950);
FORCEPROP 2 LAST CDS_LIB mstr_standard
J 0
(-1050 2875);
PAINT ORANGE (-1050 2875);
DISPLAY INVISIBLE (-1050 2875);
FORCEPROP 2 LAST PATH I3
J 0
(-875 2950);
DISPLAY 1.021277 (-875 2950);
PAINT ORANGE (-875 2950);
DISPLAY INVISIBLE (-875 2950);
FORCEADD CAP_A..1
(-1475 1000);
FORCEPROP 1 LAST TOLERANCE 10%
J 0
(-1425 950);
DISPLAY 0.617021 (-1425 950);
PAINT SKYBLUE (-1425 950);
FORCEPROP 1 LAST MATERIAL X6S
J 0
(-1425 900);
DISPLAY 0.617021 (-1425 900);
PAINT SKYBLUE (-1425 900);
FORCEPROP 1 LASTPIN (-1475 900) $PN 2
J 0
(-1465 880);
DISPLAY 0.617021 (-1465 880);
PAINT ORANGE (-1465 880);
FORCEPROP 1 LAST PACK_TYPE 0402V
J 0
(-1425 800);
DISPLAY 0.617021 (-1425 800);
PAINT SKYBLUE (-1425 800);
FORCEPROP 1 LAST PART_NUMBER D97712-004
J 0
(-1425 850);
DISPLAY 0.617021 (-1425 850);
PAINT BLUE (-1425 850);
FORCEPROP 1 LAST VOLTAGE 6.3V
J 0
(-1425 1000);
DISPLAY 0.617021 (-1425 1000);
PAINT SKYBLUE (-1425 1000);
FORCEPROP 1 LASTPIN (-1475 1100) $PN 1
J 0
(-1465 1080);
DISPLAY 0.617021 (-1465 1080);
PAINT ORANGE (-1465 1080);
FORCEPROP 1 LAST VALUE 1.0UF
J 0
(-1425 1050);
DISPLAY 0.617021 (-1425 1050);
PAINT SKYBLUE (-1425 1050);
FORCEPROP 1 LAST LOCATION C4D25
J 0
(-1425 1100);
DISPLAY 0.617021 (-1425 1100);
PAINT AQUA (-1425 1100);
FORCEPROP 2 LAST CDS_LIB dev_discrete
J 0
(-1475 1000);
PAINT ORANGE (-1475 1000);
DISPLAY INVISIBLE (-1475 1000);
FORCEPROP 2 LAST CDS_LOCATION C4D25
J 0
(-1425 1100);
DISPLAY 0.617021 (-1425 1100);
PAINT AQUA (-1425 1100);
DISPLAY INVISIBLE (-1425 1100);
FORCEPROP 2 LAST CDS_SEC 1
J 0
(-1425 1150);
PAINT ORANGE (-1425 1150);
DISPLAY INVISIBLE (-1425 1150);
FORCEPROP 1 LAST PATH I30
J 0
(-1425 1150);
DISPLAY 0.978723 (-1425 1150);
PAINT WHITE (-1425 1150);
DISPLAY INVISIBLE (-1425 1150);
FORCEPROP 2 LAST ROOM PVCCIN_CPU0_VR
J 0
(-1425 1150);
DISPLAY 1.361702 (-1425 1150);
PAINT ORANGE (-1425 1150);
DISPLAY INVISIBLE (-1425 1150);
FORCEPROP 2 LAST SEC 1
J 0
(-1425 1200);
DISPLAY 0.680851 (-1425 1200);
PAINT MONO (-1425 1200);
DISPLAY INVISIBLE (-1425 1200);
FORCEPROP 2 LAST SEC_TYPE 0402V
J 0
(-1425 1200);
DISPLAY 1.021277 (-1425 1200);
PAINT ORANGE (-1425 1200);
DISPLAY INVISIBLE (-1425 1200);
FORCEADD RES..1
(-1900 1525);
FORCEPROP 1 LAST WATTAGE 1/16W
J 2
(-1925 1375);
DISPLAY 0.617021 (-1925 1375);
PAINT SKYBLUE (-1925 1375);
FORCEPROP 1 LAST VALUE 0.0
J 2
(-2000 1425);
DISPLAY 0.617021 (-2000 1425);
PAINT SKYBLUE (-2000 1425);
FORCEPROP 1 LAST PART_NUMBER G21497-005
J 0
(-2050 1475);
DISPLAY 0.617021 (-2050 1475);
PAINT BLUE (-2050 1475);
FORCEPROP 1 LAST TOLERANCE 5%
J 0
(-1950 1425);
DISPLAY 0.617021 (-1950 1425);
PAINT SKYBLUE (-1950 1425);
FORCEPROP 1 LAST MATERIAL CHIP
J 0
(-1900 1375);
DISPLAY 0.617021 (-1900 1375);
PAINT SKYBLUE (-1900 1375);
FORCEPROP 1 LAST PACK_TYPE 0402
J 0
(-1825 1425);
DISPLAY 0.617021 (-1825 1425);
PAINT SKYBLUE (-1825 1425);
FORCEPROP 1 LASTPIN (-2000 1525) $PN 1
J 0
(-1988 1537);
DISPLAY 0.617021 (-1988 1537);
PAINT ORANGE (-1988 1537);
FORCEPROP 1 LAST LOCATION R4D53
J 0
(-1950 1575);
DISPLAY 0.617021 (-1950 1575);
PAINT AQUA (-1950 1575);
FORCEPROP 1 LASTPIN (-1800 1525) $PN 2
J 0
(-1838 1537);
DISPLAY 0.617021 (-1838 1537);
PAINT ORANGE (-1838 1537);
FORCEPROP 2 LAST CDS_LIB mstr_discrete
J 0
(-1900 1525);
PAINT ORANGE (-1900 1525);
DISPLAY INVISIBLE (-1900 1525);
FORCEPROP 1 LAST PATH I31
J 0
(-1950 1675);
DISPLAY 0.978723 (-1950 1675);
PAINT WHITE (-1950 1675);
DISPLAY INVISIBLE (-1950 1675);
FORCEPROP 2 LAST ROOM PVCCIN_CPU0_VR
J 0
(-1950 1625);
DISPLAY 1.361702 (-1950 1625);
PAINT ORANGE (-1950 1625);
DISPLAY INVISIBLE (-1950 1625);
FORCEPROP 2 LAST SEC_TYPE 0402
J 0
(-1950 1725);
DISPLAY 1.021277 (-1950 1725);
PAINT ORANGE (-1950 1725);
DISPLAY INVISIBLE (-1950 1725);
FORCEPROP 2 LAST SEC 1
J 0
(-1950 1725);
DISPLAY 0.680851 (-1950 1725);
PAINT MONO (-1950 1725);
DISPLAY INVISIBLE (-1950 1725);
FORCEPROP 2 LAST CDS_LOCATION R4D53
J 0
(-1950 1575);
DISPLAY 0.617021 (-1950 1575);
PAINT AQUA (-1950 1575);
DISPLAY INVISIBLE (-1950 1575);
FORCEADD CAP_A..1
(-1875 1000);
FORCEPROP 1 LASTPIN (-1875 900) $PN 2
J 0
(-1865 880);
DISPLAY 0.617021 (-1865 880);
PAINT ORANGE (-1865 880);
FORCEPROP 1 LAST MATERIAL X7R
J 0
(-1825 900);
DISPLAY 0.617021 (-1825 900);
PAINT SKYBLUE (-1825 900);
FORCEPROP 1 LAST PACK_TYPE 0402V
J 0
(-1825 800);
DISPLAY 0.617021 (-1825 800);
PAINT SKYBLUE (-1825 800);
FORCEPROP 1 LAST TOLERANCE 10%
J 0
(-1825 950);
DISPLAY 0.617021 (-1825 950);
PAINT SKYBLUE (-1825 950);
FORCEPROP 1 LAST PART_NUMBER A36096-030
J 0
(-1825 850);
DISPLAY 0.617021 (-1825 850);
PAINT BLUE (-1825 850);
FORCEPROP 1 LAST VOLTAGE 16V
J 0
(-1825 1000);
DISPLAY 0.617021 (-1825 1000);
PAINT SKYBLUE (-1825 1000);
FORCEPROP 1 LASTPIN (-1875 1100) $PN 1
J 0
(-1865 1080);
DISPLAY 0.617021 (-1865 1080);
PAINT ORANGE (-1865 1080);
FORCEPROP 1 LAST VALUE 0.1UF
J 0
(-1825 1050);
DISPLAY 0.617021 (-1825 1050);
PAINT SKYBLUE (-1825 1050);
FORCEPROP 1 LAST LOCATION C4D26
J 0
(-1825 1100);
DISPLAY 0.617021 (-1825 1100);
PAINT AQUA (-1825 1100);
FORCEPROP 2 LAST CDS_LIB dev_discrete
J 0
(-1875 1000);
PAINT ORANGE (-1875 1000);
DISPLAY INVISIBLE (-1875 1000);
FORCEPROP 2 LAST SEC 1
J 0
(-1825 1200);
DISPLAY 0.680851 (-1825 1200);
PAINT MONO (-1825 1200);
DISPLAY INVISIBLE (-1825 1200);
FORCEPROP 2 LAST SEC_TYPE 0402V
J 0
(-1825 1200);
DISPLAY 1.021277 (-1825 1200);
PAINT ORANGE (-1825 1200);
DISPLAY INVISIBLE (-1825 1200);
FORCEPROP 2 LAST CDS_SEC 1
J 0
(-1825 1150);
PAINT ORANGE (-1825 1150);
DISPLAY INVISIBLE (-1825 1150);
FORCEPROP 2 LAST CDS_LOCATION C4D26
J 0
(-1825 1100);
DISPLAY 0.617021 (-1825 1100);
PAINT AQUA (-1825 1100);
DISPLAY INVISIBLE (-1825 1100);
FORCEPROP 2 LAST ROOM PVCCIN_CPU0_VR
J 0
(-1825 1150);
DISPLAY 1.361702 (-1825 1150);
PAINT ORANGE (-1825 1150);
DISPLAY INVISIBLE (-1825 1150);
FORCEPROP 1 LAST PATH I32
J 0
(-1825 1150);
DISPLAY 0.978723 (-1825 1150);
PAINT WHITE (-1825 1150);
DISPLAY INVISIBLE (-1825 1150);
FORCEADD GND..1
(-1875 800);
FORCEPROP 3 LASTPIN (-1875 850) SIG_NAME GND\g
J 0
(-1865 860);
DISPLAY 0.659574 (-1865 860);
PAINT MONO (-1865 860);
DISPLAY INVISIBLE (-1865 860);
FORCEPROP 1 LAST HDL_POWER GND
J 0
(-1875 950);
DISPLAY 1.170213 (-1875 950);
PAINT GREEN (-1875 950);
DISPLAY INVISIBLE (-1875 950);
FORCEPROP 1 LAST BODY_TYPE PLUMBING
J 0
(-1920 757);
DISPLAY 0.340426 (-1920 757);
PAINT GREEN (-1920 757);
DISPLAY INVISIBLE (-1920 757);
FORCEPROP 2 LAST ROOM PVCCIN_CPU0_VR
J 0
(-2450 875);
DISPLAY 1.361702 (-2450 875);
PAINT ORANGE (-2450 875);
DISPLAY INVISIBLE (-2450 875);
FORCEPROP 1 LAST SIZE 1B
J 0
(-1800 750);
DISPLAY 1.170213 (-1800 750);
PAINT AQUA (-1800 750);
DISPLAY INVISIBLE (-1800 750);
FORCEPROP 1 LAST PATH I33
J 0
(-1800 800);
DISPLAY 0.872340 (-1800 800);
PAINT AQUA (-1800 800);
DISPLAY INVISIBLE (-1800 800);
FORCEPROP 1 LAST VOLTAGE 0
J 0
(-1875 800);
PAINT SKYBLUE (-1875 800);
DISPLAY INVISIBLE (-1875 800);
FORCEPROP 2 LAST CDS_LIB mstr_symbols
J 0
(-1875 800);
PAINT ORANGE (-1875 800);
DISPLAY INVISIBLE (-1875 800);
FORCEADD GND..1
(-3075 1550);
FORCEPROP 3 LASTPIN (-3075 1600) SIG_NAME GND\g
J 0
(-3065 1610);
DISPLAY 0.659574 (-3065 1610);
PAINT MONO (-3065 1610);
DISPLAY INVISIBLE (-3065 1610);
FORCEPROP 1 LAST HDL_POWER GND
J 0
(-3075 1700);
DISPLAY 1.170213 (-3075 1700);
PAINT GREEN (-3075 1700);
DISPLAY INVISIBLE (-3075 1700);
FORCEPROP 1 LAST BODY_TYPE PLUMBING
J 0
(-3120 1507);
DISPLAY 0.340426 (-3120 1507);
PAINT GREEN (-3120 1507);
DISPLAY INVISIBLE (-3120 1507);
FORCEPROP 2 LAST ROOM PVCCIN_CPU0_VR
J 0
(-3650 1625);
DISPLAY 1.361702 (-3650 1625);
PAINT ORANGE (-3650 1625);
DISPLAY INVISIBLE (-3650 1625);
FORCEPROP 1 LAST VOLTAGE 0
J 0
(-3075 1550);
PAINT SKYBLUE (-3075 1550);
DISPLAY INVISIBLE (-3075 1550);
FORCEPROP 2 LAST CDS_LIB mstr_symbols
J 0
(-3075 1550);
PAINT ORANGE (-3075 1550);
DISPLAY INVISIBLE (-3075 1550);
FORCEPROP 1 LAST PATH I35
J 0
(-3000 1550);
DISPLAY 0.872340 (-3000 1550);
PAINT AQUA (-3000 1550);
DISPLAY INVISIBLE (-3000 1550);
FORCEPROP 1 LAST SIZE 1B
J 0
(-3000 1500);
DISPLAY 1.170213 (-3000 1500);
PAINT AQUA (-3000 1500);
DISPLAY INVISIBLE (-3000 1500);
FORCEADD GND..1
(-3550 3725);
FORCEPROP 3 LASTPIN (-3550 3775) SIG_NAME GND\g
J 0
(-3540 3785);
DISPLAY 0.659574 (-3540 3785);
PAINT MONO (-3540 3785);
DISPLAY INVISIBLE (-3540 3785);
FORCEPROP 1 LAST HDL_POWER GND
J 0
(-3550 3875);
DISPLAY 1.170213 (-3550 3875);
PAINT GREEN (-3550 3875);
DISPLAY INVISIBLE (-3550 3875);
FORCEPROP 1 LAST BODY_TYPE PLUMBING
J 0
(-3595 3682);
DISPLAY 0.340426 (-3595 3682);
PAINT GREEN (-3595 3682);
DISPLAY INVISIBLE (-3595 3682);
FORCEPROP 2 LAST ROOM PVCCIN_CPU0_VR
J 0
(-4125 3800);
DISPLAY 1.361702 (-4125 3800);
PAINT ORANGE (-4125 3800);
DISPLAY INVISIBLE (-4125 3800);
FORCEPROP 1 LAST SIZE 1B
J 0
(-3475 3675);
DISPLAY 1.170213 (-3475 3675);
PAINT AQUA (-3475 3675);
DISPLAY INVISIBLE (-3475 3675);
FORCEPROP 1 LAST PATH I36
J 0
(-3475 3725);
DISPLAY 0.872340 (-3475 3725);
PAINT AQUA (-3475 3725);
DISPLAY INVISIBLE (-3475 3725);
FORCEPROP 2 LAST CDS_LIB mstr_symbols
J 0
(-3550 3725);
PAINT ORANGE (-3550 3725);
DISPLAY INVISIBLE (-3550 3725);
FORCEPROP 1 LAST VOLTAGE 0
J 0
(-3550 3725);
PAINT SKYBLUE (-3550 3725);
DISPLAY INVISIBLE (-3550 3725);
FORCEADD CAP_A..1
(-3550 3925);
FORCEPROP 1 LASTPIN (-3550 3825) $PN 2
J 0
(-3540 3805);
DISPLAY 0.617021 (-3540 3805);
PAINT ORANGE (-3540 3805);
FORCEPROP 1 LAST PACK_TYPE 0402V
J 0
(-3500 3725);
DISPLAY 0.617021 (-3500 3725);
PAINT SKYBLUE (-3500 3725);
FORCEPROP 1 LAST MATERIAL X6S
J 0
(-3500 3825);
DISPLAY 0.617021 (-3500 3825);
PAINT SKYBLUE (-3500 3825);
FORCEPROP 1 LASTPIN (-3550 4025) $PN 1
J 0
(-3540 4005);
DISPLAY 0.617021 (-3540 4005);
PAINT ORANGE (-3540 4005);
FORCEPROP 1 LAST VALUE 1.0UF
J 0
(-3500 3975);
DISPLAY 0.617021 (-3500 3975);
PAINT SKYBLUE (-3500 3975);
FORCEPROP 1 LAST LOCATION C4D15
J 0
(-3500 4025);
DISPLAY 0.617021 (-3500 4025);
PAINT AQUA (-3500 4025);
FORCEPROP 1 LAST TOLERANCE 10%
J 0
(-3500 3875);
DISPLAY 0.617021 (-3500 3875);
PAINT SKYBLUE (-3500 3875);
FORCEPROP 1 LAST VOLTAGE 6.3V
J 0
(-3500 3925);
DISPLAY 0.617021 (-3500 3925);
PAINT SKYBLUE (-3500 3925);
FORCEPROP 1 LAST PART_NUMBER D97712-004
J 0
(-3500 3775);
DISPLAY 0.617021 (-3500 3775);
PAINT BLUE (-3500 3775);
FORCEPROP 2 LAST CDS_LOCATION C4D15
J 0
(-3500 4025);
DISPLAY 0.617021 (-3500 4025);
PAINT AQUA (-3500 4025);
DISPLAY INVISIBLE (-3500 4025);
FORCEPROP 2 LAST CDS_LIB dev_discrete
J 0
(-3550 3925);
PAINT ORANGE (-3550 3925);
DISPLAY INVISIBLE (-3550 3925);
FORCEPROP 2 LAST ROOM PVCCIN_CPU0_VR
J 0
(-3500 4075);
DISPLAY 1.361702 (-3500 4075);
PAINT ORANGE (-3500 4075);
DISPLAY INVISIBLE (-3500 4075);
FORCEPROP 1 LAST PATH I37
J 0
(-3500 4075);
DISPLAY 0.978723 (-3500 4075);
PAINT WHITE (-3500 4075);
DISPLAY INVISIBLE (-3500 4075);
FORCEPROP 2 LAST CDS_SEC 1
J 0
(-3500 4075);
PAINT ORANGE (-3500 4075);
DISPLAY INVISIBLE (-3500 4075);
FORCEPROP 2 LAST SEC 1
J 0
(-3500 4125);
DISPLAY 0.680851 (-3500 4125);
PAINT MONO (-3500 4125);
DISPLAY INVISIBLE (-3500 4125);
FORCEPROP 2 LAST SEC_TYPE 0402V
J 0
(-3500 4125);
DISPLAY 1.021277 (-3500 4125);
PAINT ORANGE (-3500 4125);
DISPLAY INVISIBLE (-3500 4125);
FORCEADD GND..1
(-3950 3725);
FORCEPROP 3 LASTPIN (-3950 3775) SIG_NAME GND\g
J 0
(-3940 3785);
DISPLAY 0.659574 (-3940 3785);
PAINT MONO (-3940 3785);
DISPLAY INVISIBLE (-3940 3785);
FORCEPROP 1 LAST HDL_POWER GND
J 0
(-3950 3875);
DISPLAY 1.170213 (-3950 3875);
PAINT GREEN (-3950 3875);
DISPLAY INVISIBLE (-3950 3875);
FORCEPROP 1 LAST BODY_TYPE PLUMBING
J 0
(-3995 3682);
DISPLAY 0.340426 (-3995 3682);
PAINT GREEN (-3995 3682);
DISPLAY INVISIBLE (-3995 3682);
FORCEPROP 2 LAST ROOM PVCCIN_CPU0_VR
J 0
(-4525 3800);
DISPLAY 1.361702 (-4525 3800);
PAINT ORANGE (-4525 3800);
DISPLAY INVISIBLE (-4525 3800);
FORCEPROP 1 LAST VOLTAGE 0
J 0
(-3950 3725);
PAINT SKYBLUE (-3950 3725);
DISPLAY INVISIBLE (-3950 3725);
FORCEPROP 1 LAST SIZE 1B
J 0
(-3875 3675);
DISPLAY 1.170213 (-3875 3675);
PAINT AQUA (-3875 3675);
DISPLAY INVISIBLE (-3875 3675);
FORCEPROP 2 LAST CDS_LIB mstr_symbols
J 0
(-3950 3725);
PAINT ORANGE (-3950 3725);
DISPLAY INVISIBLE (-3950 3725);
FORCEPROP 1 LAST PATH I38
J 0
(-3875 3725);
DISPLAY 0.872340 (-3875 3725);
PAINT AQUA (-3875 3725);
DISPLAY INVISIBLE (-3875 3725);
FORCEADD CAP_A..1
(-3950 3925);
FORCEPROP 1 LASTPIN (-3950 3825) $PN 2
J 0
(-3940 3805);
DISPLAY 0.617021 (-3940 3805);
PAINT ORANGE (-3940 3805);
FORCEPROP 1 LASTPIN (-3950 4025) $PN 1
J 0
(-3940 4005);
DISPLAY 0.617021 (-3940 4005);
PAINT ORANGE (-3940 4005);
FORCEPROP 1 LAST MATERIAL X7R
J 0
(-3900 3825);
DISPLAY 0.617021 (-3900 3825);
PAINT SKYBLUE (-3900 3825);
FORCEPROP 1 LAST VOLTAGE 16V
J 0
(-3900 3925);
DISPLAY 0.617021 (-3900 3925);
PAINT SKYBLUE (-3900 3925);
FORCEPROP 1 LAST PACK_TYPE 0402V
J 0
(-3900 3725);
DISPLAY 0.617021 (-3900 3725);
PAINT SKYBLUE (-3900 3725);
FORCEPROP 1 LAST TOLERANCE 10%
J 0
(-3900 3875);
DISPLAY 0.617021 (-3900 3875);
PAINT SKYBLUE (-3900 3875);
FORCEPROP 1 LAST VALUE 0.1UF
J 0
(-3900 3975);
DISPLAY 0.617021 (-3900 3975);
PAINT SKYBLUE (-3900 3975);
FORCEPROP 1 LAST LOCATION C4D19
J 0
(-3900 4025);
DISPLAY 0.617021 (-3900 4025);
PAINT AQUA (-3900 4025);
FORCEPROP 1 LAST PART_NUMBER A36096-030
J 0
(-3900 3775);
DISPLAY 0.617021 (-3900 3775);
PAINT BLUE (-3900 3775);
FORCEPROP 2 LAST CDS_LOCATION C4D19
J 0
(-3900 4025);
DISPLAY 0.617021 (-3900 4025);
PAINT AQUA (-3900 4025);
DISPLAY INVISIBLE (-3900 4025);
FORCEPROP 2 LAST CDS_LIB dev_discrete
J 0
(-3950 3925);
PAINT ORANGE (-3950 3925);
DISPLAY INVISIBLE (-3950 3925);
FORCEPROP 2 LAST CDS_SEC 1
J 0
(-3900 4075);
PAINT ORANGE (-3900 4075);
DISPLAY INVISIBLE (-3900 4075);
FORCEPROP 2 LAST ROOM PVCCIN_CPU0_VR
J 0
(-3900 4075);
DISPLAY 1.361702 (-3900 4075);
PAINT ORANGE (-3900 4075);
DISPLAY INVISIBLE (-3900 4075);
FORCEPROP 1 LAST PATH I39
J 0
(-3900 4075);
DISPLAY 0.978723 (-3900 4075);
PAINT WHITE (-3900 4075);
DISPLAY INVISIBLE (-3900 4075);
FORCEPROP 2 LAST SEC 1
J 0
(-3900 4125);
DISPLAY 0.680851 (-3900 4125);
PAINT MONO (-3900 4125);
DISPLAY INVISIBLE (-3900 4125);
FORCEPROP 2 LAST SEC_TYPE 0402V
J 0
(-3900 4125);
DISPLAY 1.021277 (-3900 4125);
PAINT ORANGE (-3900 4125);
DISPLAY INVISIBLE (-3900 4125);
FORCEADD OFFPAGE..2
(-1050 2775);
FORCEPROP 2 LAST $XR0 201 
J 0
(-861 2775);
DISPLAY 0.638298 (-861 2775);
PAINT MONO (-861 2775);
FORCEPROP 1 LAST COMMENT_BODY TRUE
J 0
(-1095 2680);
DISPLAY 1.170213 (-1095 2680);
PAINT GREEN (-1095 2680);
DISPLAY INVISIBLE (-1095 2680);
FORCEPROP 1 LAST OFFPAGE TRUE
J 0
(-725 2650);
DISPLAY 1.170213 (-725 2650);
PAINT GREEN (-725 2650);
DISPLAY INVISIBLE (-725 2650);
FORCEPROP 2 LAST ROOM PVCCIN_CPU0_VR
J 0
(-1475 2850);
DISPLAY 1.361702 (-1475 2850);
PAINT ORANGE (-1475 2850);
DISPLAY INVISIBLE (-1475 2850);
FORCEPROP 2 LAST CDS_LIB mstr_standard
J 0
(-1050 2775);
PAINT ORANGE (-1050 2775);
DISPLAY INVISIBLE (-1050 2775);
FORCEPROP 2 LAST PATH I4
J 0
(-875 2850);
DISPLAY 1.021277 (-875 2850);
PAINT ORANGE (-875 2850);
DISPLAY INVISIBLE (-875 2850);
FORCEADD RES..2
(-4250 4275);
FORCEPROP 1 LASTPIN (-4250 4175) $PN 2
J 0
(-4245 4185);
DISPLAY 0.617021 (-4245 4185);
PAINT ORANGE (-4245 4185);
FORCEPROP 1 LAST TOLERANCE 5%
J 0
(-4205 4300);
DISPLAY 0.617021 (-4205 4300);
PAINT SKYBLUE (-4205 4300);
FORCEPROP 1 LASTPIN (-4250 4375) $PN 1
J 0
(-4245 4337);
DISPLAY 0.617021 (-4245 4337);
PAINT ORANGE (-4245 4337);
FORCEPROP 1 LAST VALUE 0.0
J 0
(-4205 4350);
DISPLAY 0.617021 (-4205 4350);
PAINT SKYBLUE (-4205 4350);
FORCEPROP 1 LAST WATTAGE 1/16W
J 0
(-4210 4250);
DISPLAY 0.617021 (-4210 4250);
PAINT SKYBLUE (-4210 4250);
FORCEPROP 1 LAST MATERIAL CHIP
J 0
(-4210 4200);
DISPLAY 0.617021 (-4210 4200);
PAINT SKYBLUE (-4210 4200);
FORCEPROP 1 LAST PACK_TYPE 0402
J 0
(-4210 4100);
DISPLAY 0.617021 (-4210 4100);
PAINT SKYBLUE (-4210 4100);
FORCEPROP 1 LAST PART_NUMBER G21497-005
J 0
(-4210 4150);
DISPLAY 0.617021 (-4210 4150);
PAINT BLUE (-4210 4150);
FORCEPROP 1 LAST LOCATION R4D26
J 0
(-4205 4400);
DISPLAY 0.617021 (-4205 4400);
PAINT AQUA (-4205 4400);
FORCEPROP 2 LAST CDS_LIB mstr_discrete
J 0
(-4250 4275);
PAINT ORANGE (-4250 4275);
DISPLAY INVISIBLE (-4250 4275);
FORCEPROP 2 LAST SEC_TYPE 0402
J 0
(-4200 4500);
DISPLAY 1.021277 (-4200 4500);
PAINT ORANGE (-4200 4500);
DISPLAY INVISIBLE (-4200 4500);
FORCEPROP 2 LAST SEC 1
J 0
(-4200 4500);
DISPLAY 0.680851 (-4200 4500);
PAINT MONO (-4200 4500);
DISPLAY INVISIBLE (-4200 4500);
FORCEPROP 2 LAST CDS_LOCATION R4D26
J 0
(-4205 4400);
DISPLAY 0.617021 (-4205 4400);
PAINT AQUA (-4205 4400);
DISPLAY INVISIBLE (-4205 4400);
FORCEPROP 1 LAST PATH I40
J 0
(-4200 4450);
DISPLAY 0.978723 (-4200 4450);
PAINT WHITE (-4200 4450);
DISPLAY INVISIBLE (-4200 4450);
FORCEPROP 2 LAST ROOM PVCCIN_CPU0_VR
J 0
(-4200 4450);
DISPLAY 1.361702 (-4200 4450);
PAINT ORANGE (-4200 4450);
DISPLAY INVISIBLE (-4200 4450);
FORCEADD GND..1
(-4400 575);
FORCEPROP 3 LASTPIN (-4400 625) SIG_NAME GND\g
J 0
(-4390 635);
DISPLAY 0.659574 (-4390 635);
PAINT MONO (-4390 635);
DISPLAY INVISIBLE (-4390 635);
FORCEPROP 1 LAST HDL_POWER GND
J 0
(-4400 725);
DISPLAY 1.170213 (-4400 725);
PAINT GREEN (-4400 725);
DISPLAY INVISIBLE (-4400 725);
FORCEPROP 1 LAST BODY_TYPE PLUMBING
J 0
(-4445 532);
DISPLAY 0.340426 (-4445 532);
PAINT GREEN (-4445 532);
DISPLAY INVISIBLE (-4445 532);
FORCEPROP 2 LAST ROOM PVCCIN_CPU0_VR
J 0
(-4975 650);
DISPLAY 1.361702 (-4975 650);
PAINT ORANGE (-4975 650);
DISPLAY INVISIBLE (-4975 650);
FORCEPROP 2 LAST CDS_LIB mstr_symbols
J 0
(-4400 575);
PAINT ORANGE (-4400 575);
DISPLAY INVISIBLE (-4400 575);
FORCEPROP 1 LAST VOLTAGE 0
J 0
(-4400 575);
PAINT SKYBLUE (-4400 575);
DISPLAY INVISIBLE (-4400 575);
FORCEPROP 1 LAST PATH I48
J 0
(-4325 575);
DISPLAY 0.872340 (-4325 575);
PAINT AQUA (-4325 575);
DISPLAY INVISIBLE (-4325 575);
FORCEPROP 1 LAST SIZE 1B
J 0
(-4325 525);
DISPLAY 1.170213 (-4325 525);
PAINT AQUA (-4325 525);
DISPLAY INVISIBLE (-4325 525);
FORCEADD OFFPAGE..3
(-1075 2725);
FORCEPROP 2 LAST $XR0 21 
J 0
(-861 2725);
DISPLAY 0.638298 (-861 2725);
PAINT MONO (-861 2725);
FORCEPROP 2 LAST $XR1 194 
J 0
(-771 2725);
DISPLAY 0.638298 (-771 2725);
PAINT MONO (-771 2725);
FORCEPROP 2 LAST $XR2 211 
J 0
(-651 2725);
DISPLAY 0.638298 (-651 2725);
PAINT MONO (-651 2725);
FORCEPROP 1 LAST COMMENT_BODY TRUE
J 0
(-1125 2625);
DISPLAY 1.170213 (-1125 2625);
PAINT GREEN (-1125 2625);
DISPLAY INVISIBLE (-1125 2625);
FORCEPROP 1 LAST OFFPAGE TRUE
J 0
(-750 2600);
DISPLAY 1.170213 (-750 2600);
PAINT GREEN (-750 2600);
DISPLAY INVISIBLE (-750 2600);
FORCEPROP 2 LAST ROOM PVCCIN_CPU0_VR
J 0
(-1475 2800);
DISPLAY 1.361702 (-1475 2800);
PAINT ORANGE (-1475 2800);
DISPLAY INVISIBLE (-1475 2800);
FORCEPROP 2 LAST CDS_LIB mstr_standard
J 0
(-1075 2725);
PAINT ORANGE (-1075 2725);
DISPLAY INVISIBLE (-1075 2725);
FORCEPROP 2 LAST PATH I5
J 0
(-875 2800);
DISPLAY 1.021277 (-875 2800);
PAINT ORANGE (-875 2800);
DISPLAY INVISIBLE (-875 2800);
FORCEADD GND..1
(-4725 575);
FORCEPROP 3 LASTPIN (-4725 625) SIG_NAME GND\g
J 0
(-4715 635);
DISPLAY 0.659574 (-4715 635);
PAINT MONO (-4715 635);
DISPLAY INVISIBLE (-4715 635);
FORCEPROP 1 LAST HDL_POWER GND
J 0
(-4725 725);
DISPLAY 1.170213 (-4725 725);
PAINT GREEN (-4725 725);
DISPLAY INVISIBLE (-4725 725);
FORCEPROP 1 LAST BODY_TYPE PLUMBING
J 0
(-4770 532);
DISPLAY 0.340426 (-4770 532);
PAINT GREEN (-4770 532);
DISPLAY INVISIBLE (-4770 532);
FORCEPROP 2 LAST ROOM PVCCIN_CPU0_VR
J 0
(-5300 650);
DISPLAY 1.361702 (-5300 650);
PAINT ORANGE (-5300 650);
DISPLAY INVISIBLE (-5300 650);
FORCEPROP 1 LAST PATH I50
J 0
(-4650 575);
DISPLAY 0.872340 (-4650 575);
PAINT AQUA (-4650 575);
DISPLAY INVISIBLE (-4650 575);
FORCEPROP 2 LAST CDS_LIB mstr_symbols
J 0
(-4725 575);
PAINT ORANGE (-4725 575);
DISPLAY INVISIBLE (-4725 575);
FORCEPROP 1 LAST SIZE 1B
J 0
(-4650 525);
DISPLAY 1.170213 (-4650 525);
PAINT AQUA (-4650 525);
DISPLAY INVISIBLE (-4650 525);
FORCEPROP 1 LAST VOLTAGE 0
J 0
(-4725 575);
PAINT SKYBLUE (-4725 575);
DISPLAY INVISIBLE (-4725 575);
FORCEADD PVCCIO_CPU0..1
(-5325 4825);
FORCEPROP 3 LASTPIN (-5325 4775) SIG_NAME PVCCIO_CPU0\g
J 0
(-5315 4785);
DISPLAY 0.659574 (-5315 4785);
PAINT MONO (-5315 4785);
DISPLAY INVISIBLE (-5315 4785);
FORCEPROP 1 LAST HDL_POWER PVCCIO_CPU0
J 1
(-5325 4875);
DISPLAY 0.872340 (-5325 4875);
PAINT GREEN (-5325 4875);
DISPLAY INVISIBLE (-5325 4875);
FORCEPROP 1 LAST BODY_TYPE PLUMBING
J 0
(-5370 4782);
DISPLAY 0.340426 (-5370 4782);
PAINT GREEN (-5370 4782);
DISPLAY INVISIBLE (-5370 4782);
FORCEPROP 1 LAST PATH I51
J 0
(-5275 4850);
DISPLAY 0.872340 (-5275 4850);
PAINT AQUA (-5275 4850);
DISPLAY INVISIBLE (-5275 4850);
FORCEPROP 2 LAST CDS_LIB mstr_symbols
J 0
(-5325 4825);
PAINT ORANGE (-5325 4825);
DISPLAY INVISIBLE (-5325 4825);
FORCEPROP 1 LAST VOLTAGE 1.1V
J 0
(-5370 4782);
DISPLAY 0.340426 (-5370 4782);
PAINT SKYBLUE (-5370 4782);
DISPLAY INVISIBLE (-5370 4782);
FORCEADD RES..2
(-5650 4275);
FORCEPROP 1 LASTPIN (-5650 4375) $PN 1
J 0
(-5645 4337);
DISPLAY 0.617021 (-5645 4337);
PAINT ORANGE (-5645 4337);
FORCEPROP 1 LASTPIN (-5650 4175) $PN 2
J 0
(-5645 4185);
DISPLAY 0.617021 (-5645 4185);
PAINT ORANGE (-5645 4185);
FORCEPROP 1 LAST WATTAGE 1/16W
J 0
(-5610 4250);
DISPLAY 0.617021 (-5610 4250);
PAINT SKYBLUE (-5610 4250);
FORCEPROP 1 LAST MATERIAL CHIP
J 0
(-5610 4200);
DISPLAY 0.617021 (-5610 4200);
PAINT SKYBLUE (-5610 4200);
FORCEPROP 1 LAST PACK_TYPE 0402
J 0
(-5610 4100);
DISPLAY 0.617021 (-5610 4100);
PAINT SKYBLUE (-5610 4100);
FORCEPROP 1 LAST TOLERANCE 1%
J 0
(-5605 4300);
DISPLAY 0.617021 (-5605 4300);
PAINT SKYBLUE (-5605 4300);
FORCEPROP 1 LAST VALUE 49.9
J 0
(-5605 4350);
DISPLAY 0.617021 (-5605 4350);
PAINT SKYBLUE (-5605 4350);
FORCEPROP 1 LAST LOCATION R4E9
J 0
(-5605 4400);
DISPLAY 0.617021 (-5605 4400);
PAINT AQUA (-5605 4400);
FORCEPROP 1 LAST PART_NUMBER G21796-047
J 0
(-5610 4150);
DISPLAY 0.617021 (-5610 4150);
PAINT BLUE (-5610 4150);
FORCEPROP 2 LAST CDS_LIB mstr_discrete
J 0
(-5650 4275);
PAINT ORANGE (-5650 4275);
DISPLAY INVISIBLE (-5650 4275);
FORCEPROP 2 LAST SEC_TYPE 0402
J 0
(-5600 4500);
DISPLAY 1.021277 (-5600 4500);
PAINT ORANGE (-5600 4500);
DISPLAY INVISIBLE (-5600 4500);
FORCEPROP 2 LAST SEC 1
J 0
(-5600 4500);
DISPLAY 0.680851 (-5600 4500);
PAINT MONO (-5600 4500);
DISPLAY INVISIBLE (-5600 4500);
FORCEPROP 2 LAST CDS_LOCATION R4E9
J 0
(-5605 4400);
DISPLAY 0.617021 (-5605 4400);
PAINT AQUA (-5605 4400);
DISPLAY INVISIBLE (-5605 4400);
FORCEPROP 1 LAST PATH I52
J 0
(-5600 4450);
DISPLAY 0.978723 (-5600 4450);
PAINT WHITE (-5600 4450);
DISPLAY INVISIBLE (-5600 4450);
FORCEPROP 2 LAST ROOM PVCCIN_CPU0_VR
J 0
(-5600 4450);
DISPLAY 1.361702 (-5600 4450);
PAINT ORANGE (-5600 4450);
DISPLAY INVISIBLE (-5600 4450);
FORCEADD VCC_CORE..1
(-6050 4825);
FORCEPROP 3 LASTPIN (-6050 4775) SIG_NAME VR_FET_SW_P12V_STBY_PVCCIN_CPU0\g
J 0
(-6040 4785);
DISPLAY 0.659574 (-6040 4785);
PAINT MONO (-6040 4785);
DISPLAY INVISIBLE (-6040 4785);
FORCEPROP 1 LAST HDL_POWER VR_FET_SW_P12V_STBY_PVCCIN_CPU0
J 1
(-6075 4875);
DISPLAY 0.617021 (-6075 4875);
PAINT GREEN (-6075 4875);
FORCEPROP 1 LAST PATH I53
J 0
(-6000 4850);
DISPLAY 0.872340 (-6000 4850);
PAINT AQUA (-6000 4850);
DISPLAY INVISIBLE (-6000 4850);
FORCEPROP 2 LAST CDS_LIB mstr_symbols
J 0
(-6050 4825);
PAINT ORANGE (-6050 4825);
DISPLAY INVISIBLE (-6050 4825);
FORCEADD RES..2
(-6050 4625);
FORCEPROP 1 LASTPIN (-6050 4525) $PN 2
J 0
(-6045 4535);
DISPLAY 0.617021 (-6045 4535);
PAINT ORANGE (-6045 4535);
FORCEPROP 1 LAST PACK_TYPE 0402
J 0
(-6010 4450);
DISPLAY 0.617021 (-6010 4450);
PAINT SKYBLUE (-6010 4450);
FORCEPROP 1 LAST MATERIAL CHIP
J 0
(-6010 4550);
DISPLAY 0.617021 (-6010 4550);
PAINT SKYBLUE (-6010 4550);
FORCEPROP 1 LAST PART_NUMBER G21796-160
J 0
(-6010 4500);
DISPLAY 0.617021 (-6010 4500);
PAINT BLUE (-6010 4500);
FORCEPROP 1 LAST WATTAGE 1/16W
J 0
(-6010 4600);
DISPLAY 0.617021 (-6010 4600);
PAINT SKYBLUE (-6010 4600);
FORCEPROP 1 LASTPIN (-6050 4725) $PN 1
J 0
(-6045 4687);
DISPLAY 0.617021 (-6045 4687);
PAINT ORANGE (-6045 4687);
FORCEPROP 1 LAST TOLERANCE 1%
J 0
(-6005 4650);
DISPLAY 0.617021 (-6005 4650);
PAINT SKYBLUE (-6005 4650);
FORCEPROP 1 LAST LOCATION R4D27
J 0
(-6005 4750);
DISPLAY 0.617021 (-6005 4750);
PAINT AQUA (-6005 4750);
FORCEPROP 1 LAST VALUE 100.0K
J 0
(-6005 4700);
DISPLAY 0.617021 (-6005 4700);
PAINT SKYBLUE (-6005 4700);
FORCEPROP 2 LAST CDS_LIB mstr_discrete
J 0
(-6050 4625);
PAINT ORANGE (-6050 4625);
DISPLAY INVISIBLE (-6050 4625);
FORCEPROP 2 LAST CDS_LOCATION R4D27
J 0
(-6005 4750);
DISPLAY 0.617021 (-6005 4750);
PAINT AQUA (-6005 4750);
DISPLAY INVISIBLE (-6005 4750);
FORCEPROP 1 LAST PATH I54
J 0
(-6000 4800);
DISPLAY 0.978723 (-6000 4800);
PAINT WHITE (-6000 4800);
DISPLAY INVISIBLE (-6000 4800);
FORCEPROP 2 LAST ROOM PVCCIN_CPU0_VR
J 0
(-6000 4800);
DISPLAY 1.361702 (-6000 4800);
PAINT ORANGE (-6000 4800);
DISPLAY INVISIBLE (-6000 4800);
FORCEPROP 2 LAST SEC 1
J 0
(-6000 4850);
DISPLAY 0.680851 (-6000 4850);
PAINT MONO (-6000 4850);
DISPLAY INVISIBLE (-6000 4850);
FORCEPROP 2 LAST SEC_TYPE 0402
J 0
(-6000 4850);
DISPLAY 1.021277 (-6000 4850);
PAINT ORANGE (-6000 4850);
DISPLAY INVISIBLE (-6000 4850);
FORCEADD RES..2
(-6050 4200);
FORCEPROP 1 LAST PACK_TYPE 0402
J 0
(-6010 4025);
DISPLAY 0.617021 (-6010 4025);
PAINT SKYBLUE (-6010 4025);
FORCEPROP 1 LAST PART_NUMBER G21796-003
J 0
(-6010 4075);
DISPLAY 0.617021 (-6010 4075);
PAINT BLUE (-6010 4075);
FORCEPROP 1 LASTPIN (-6050 4100) $PN 2
J 0
(-6045 4110);
DISPLAY 0.617021 (-6045 4110);
PAINT ORANGE (-6045 4110);
FORCEPROP 1 LASTPIN (-6050 4300) $PN 1
J 0
(-6045 4262);
DISPLAY 0.617021 (-6045 4262);
PAINT ORANGE (-6045 4262);
FORCEPROP 1 LAST VALUE 1.5K
J 0
(-6005 4275);
DISPLAY 0.617021 (-6005 4275);
PAINT SKYBLUE (-6005 4275);
FORCEPROP 1 LAST TOLERANCE 1%
J 0
(-6005 4225);
DISPLAY 0.617021 (-6005 4225);
PAINT SKYBLUE (-6005 4225);
FORCEPROP 1 LAST MATERIAL CHIP
J 0
(-6010 4125);
DISPLAY 0.617021 (-6010 4125);
PAINT SKYBLUE (-6010 4125);
FORCEPROP 1 LAST WATTAGE 1/16W
J 0
(-6010 4175);
DISPLAY 0.617021 (-6010 4175);
PAINT SKYBLUE (-6010 4175);
FORCEPROP 1 LAST LOCATION R4D32
J 0
(-6005 4325);
DISPLAY 0.617021 (-6005 4325);
PAINT AQUA (-6005 4325);
FORCEPROP 2 LAST CDS_LIB mstr_discrete
J 0
(-6050 4200);
PAINT ORANGE (-6050 4200);
DISPLAY INVISIBLE (-6050 4200);
FORCEPROP 2 LAST CDS_LOCATION R4D32
J 0
(-6005 4325);
DISPLAY 0.617021 (-6005 4325);
PAINT AQUA (-6005 4325);
DISPLAY INVISIBLE (-6005 4325);
FORCEPROP 2 LAST SEC_TYPE 0402
J 0
(-6000 4425);
DISPLAY 1.021277 (-6000 4425);
PAINT ORANGE (-6000 4425);
DISPLAY INVISIBLE (-6000 4425);
FORCEPROP 2 LAST SEC 1
J 0
(-6000 4425);
DISPLAY 0.680851 (-6000 4425);
PAINT MONO (-6000 4425);
DISPLAY INVISIBLE (-6000 4425);
FORCEPROP 1 LAST PATH I55
J 0
(-6000 4375);
DISPLAY 0.978723 (-6000 4375);
PAINT WHITE (-6000 4375);
DISPLAY INVISIBLE (-6000 4375);
FORCEPROP 2 LAST ROOM PVCCIN_CPU0_VR
J 0
(-6000 4375);
DISPLAY 1.361702 (-6000 4375);
PAINT ORANGE (-6000 4375);
DISPLAY INVISIBLE (-6000 4375);
FORCEADD RES..1
(-5400 3950);
FORCEPROP 1 LAST VALUE 150.0
J 2
(-5450 3900);
DISPLAY 0.617021 (-5450 3900);
PAINT SKYBLUE (-5450 3900);
FORCEPROP 1 LAST WATTAGE 1/16W
J 2
(-5450 4000);
DISPLAY 0.617021 (-5450 4000);
PAINT SKYBLUE (-5450 4000);
FORCEPROP 1 LASTPIN (-5500 3950) $PN 1
J 0
(-5488 3962);
DISPLAY 0.617021 (-5488 3962);
PAINT ORANGE (-5488 3962);
FORCEPROP 1 LAST TOLERANCE 1%
J 0
(-5400 3900);
DISPLAY 0.617021 (-5400 3900);
PAINT SKYBLUE (-5400 3900);
FORCEPROP 1 LAST PART_NUMBER G21796-009
J 0
(-5450 4050);
DISPLAY 0.617021 (-5450 4050);
PAINT BLUE (-5450 4050);
FORCEPROP 1 LAST LOCATION R4E6
J 0
(-5450 4000);
DISPLAY 0.617021 (-5450 4000);
PAINT AQUA (-5450 4000);
FORCEPROP 1 LAST PACK_TYPE 0402
J 0
(-5300 3900);
DISPLAY 0.617021 (-5300 3900);
PAINT SKYBLUE (-5300 3900);
FORCEPROP 1 LAST MATERIAL CHIP
J 0
(-5300 4000);
DISPLAY 0.617021 (-5300 4000);
PAINT SKYBLUE (-5300 4000);
FORCEPROP 1 LASTPIN (-5300 3950) $PN 2
J 0
(-5338 3962);
DISPLAY 0.617021 (-5338 3962);
PAINT ORANGE (-5338 3962);
FORCEPROP 2 LAST CDS_LIB mstr_discrete
J 0
(-5400 3950);
PAINT ORANGE (-5400 3950);
DISPLAY INVISIBLE (-5400 3950);
FORCEPROP 2 LAST CDS_LOCATION R4E6
J 0
(-5450 4000);
DISPLAY 0.617021 (-5450 4000);
PAINT AQUA (-5450 4000);
DISPLAY INVISIBLE (-5450 4000);
FORCEPROP 2 LAST SEC_TYPE 0402
J 0
(-5450 4150);
DISPLAY 1.021277 (-5450 4150);
PAINT ORANGE (-5450 4150);
DISPLAY INVISIBLE (-5450 4150);
FORCEPROP 2 LAST SEC 1
J 0
(-5450 4150);
DISPLAY 0.680851 (-5450 4150);
PAINT MONO (-5450 4150);
DISPLAY INVISIBLE (-5450 4150);
FORCEPROP 1 LAST PATH I56
J 0
(-5450 4100);
DISPLAY 0.978723 (-5450 4100);
PAINT WHITE (-5450 4100);
DISPLAY INVISIBLE (-5450 4100);
FORCEPROP 2 LAST ROOM PVCCIN_CPU0_VR
J 0
(-5500 4175);
DISPLAY 1.361702 (-5500 4175);
PAINT ORANGE (-5500 4175);
DISPLAY INVISIBLE (-5500 4175);
FORCEADD GND..1
(-6050 3975);
FORCEPROP 3 LASTPIN (-6050 4025) SIG_NAME GND\g
J 0
(-6040 4035);
DISPLAY 0.659574 (-6040 4035);
PAINT MONO (-6040 4035);
DISPLAY INVISIBLE (-6040 4035);
FORCEPROP 1 LAST HDL_POWER GND
J 0
(-6050 4125);
DISPLAY 1.170213 (-6050 4125);
PAINT GREEN (-6050 4125);
DISPLAY INVISIBLE (-6050 4125);
FORCEPROP 1 LAST BODY_TYPE PLUMBING
J 0
(-6095 3932);
DISPLAY 0.340426 (-6095 3932);
PAINT GREEN (-6095 3932);
DISPLAY INVISIBLE (-6095 3932);
FORCEPROP 1 LAST PATH I58
J 0
(-5975 3975);
DISPLAY 0.872340 (-5975 3975);
PAINT AQUA (-5975 3975);
DISPLAY INVISIBLE (-5975 3975);
FORCEPROP 2 LAST CDS_LIB mstr_symbols
J 0
(-6050 3975);
PAINT ORANGE (-6050 3975);
DISPLAY INVISIBLE (-6050 3975);
FORCEPROP 1 LAST SIZE 1B
J 0
(-5975 3925);
DISPLAY 1.170213 (-5975 3925);
PAINT AQUA (-5975 3925);
DISPLAY INVISIBLE (-5975 3925);
FORCEPROP 1 LAST VOLTAGE 0
J 0
(-6050 3975);
PAINT SKYBLUE (-6050 3975);
DISPLAY INVISIBLE (-6050 3975);
FORCEPROP 2 LAST ROOM PVCCIN_CPU0_VR
J 0
(-6625 4050);
DISPLAY 1.361702 (-6625 4050);
PAINT ORANGE (-6625 4050);
DISPLAY INVISIBLE (-6625 4050);
FORCEADD OFFPAGE..2
(-1050 2675);
FORCEPROP 2 LAST $XR0 190 
J 0
(-861 2675);
DISPLAY 0.638298 (-861 2675);
PAINT MONO (-861 2675);
FORCEPROP 1 LAST COMMENT_BODY TRUE
J 0
(-1095 2580);
DISPLAY 1.170213 (-1095 2580);
PAINT GREEN (-1095 2580);
DISPLAY INVISIBLE (-1095 2580);
FORCEPROP 1 LAST OFFPAGE TRUE
J 0
(-725 2550);
DISPLAY 1.170213 (-725 2550);
PAINT GREEN (-725 2550);
DISPLAY INVISIBLE (-725 2550);
FORCEPROP 2 LAST ROOM PVCCIN_CPU0_VR
J 0
(-1475 2750);
DISPLAY 1.361702 (-1475 2750);
PAINT ORANGE (-1475 2750);
DISPLAY INVISIBLE (-1475 2750);
FORCEPROP 2 LAST CDS_LIB mstr_standard
J 0
(-1050 2675);
PAINT ORANGE (-1050 2675);
DISPLAY INVISIBLE (-1050 2675);
FORCEPROP 2 LAST PATH I6
J 0
(-875 2750);
DISPLAY 1.021277 (-875 2750);
PAINT ORANGE (-875 2750);
DISPLAY INVISIBLE (-875 2750);
FORCEADD CAP..1
R 2
(-6300 4225);
FORCEPROP 1 LAST PACK_TYPE 0402LF
J 2
(-6350 4025);
DISPLAY 0.617021 (-6350 4025);
PAINT SKYBLUE (-6350 4025);
FORCEPROP 1 LAST PART_NUMBER A36096-046
J 2
(-6350 4075);
DISPLAY 0.617021 (-6350 4075);
PAINT BLUE (-6350 4075);
FORCEPROP 1 LAST MATERIAL X7R
J 2
(-6350 4125);
DISPLAY 0.617021 (-6350 4125);
PAINT SKYBLUE (-6350 4125);
FORCEPROP 1 LAST VOLTAGE 50V
J 2
(-6350 4225);
DISPLAY 0.617021 (-6350 4225);
PAINT SKYBLUE (-6350 4225);
FORCEPROP 1 LAST TOLERANCE 10%
J 2
(-6350 4175);
DISPLAY 0.617021 (-6350 4175);
PAINT SKYBLUE (-6350 4175);
FORCEPROP 1 LAST VALUE 1000PF
J 2
(-6350 4275);
DISPLAY 0.617021 (-6350 4275);
PAINT SKYBLUE (-6350 4275);
FORCEPROP 1 LAST LOCATION C4D20
J 2
(-6350 4325);
DISPLAY 0.617021 (-6350 4325);
PAINT AQUA (-6350 4325);
FORCEPROP 1 LASTPIN (-6300 4125) $PN 2
J 2
(-6310 4105);
DISPLAY 0.617021 (-6310 4105);
PAINT ORANGE (-6310 4105);
FORCEPROP 1 LASTPIN (-6300 4325) $PN 1
J 2
(-6310 4305);
DISPLAY 0.617021 (-6310 4305);
PAINT ORANGE (-6310 4305);
FORCEPROP 2 LAST CDS_LIB mstr_discrete
J 2
(-6300 4225);
PAINT ORANGE (-6300 4225);
DISPLAY INVISIBLE (-6300 4225);
FORCEPROP 2 LAST CDS_LOCATION C4D20
J 2
(-6350 4325);
DISPLAY 0.617021 (-6350 4325);
PAINT AQUA (-6350 4325);
DISPLAY INVISIBLE (-6350 4325);
FORCEPROP 2 LAST SEC_TYPE 0402LF
J 0
(-6350 4425);
DISPLAY 1.021277 (-6350 4425);
PAINT ORANGE (-6350 4425);
DISPLAY INVISIBLE (-6350 4425);
FORCEPROP 2 LAST SEC 1
J 0
(-6350 4425);
DISPLAY 0.680851 (-6350 4425);
PAINT MONO (-6350 4425);
DISPLAY INVISIBLE (-6350 4425);
FORCEPROP 1 LAST PATH I60
J 2
(-6350 4375);
DISPLAY 0.978723 (-6350 4375);
PAINT WHITE (-6350 4375);
DISPLAY INVISIBLE (-6350 4375);
FORCEPROP 2 LAST ROOM PVCCIN_CPU0_VR
J 0
(-6350 4375);
DISPLAY 1.361702 (-6350 4375);
PAINT ORANGE (-6350 4375);
DISPLAY INVISIBLE (-6350 4375);
FORCEADD GND..1
(-6300 4000);
FORCEPROP 3 LASTPIN (-6300 4050) SIG_NAME GND\g
J 0
(-6290 4060);
DISPLAY 0.659574 (-6290 4060);
PAINT MONO (-6290 4060);
DISPLAY INVISIBLE (-6290 4060);
FORCEPROP 1 LAST HDL_POWER GND
J 0
(-6300 4150);
DISPLAY 1.170213 (-6300 4150);
PAINT GREEN (-6300 4150);
DISPLAY INVISIBLE (-6300 4150);
FORCEPROP 1 LAST BODY_TYPE PLUMBING
J 0
(-6345 3957);
DISPLAY 0.340426 (-6345 3957);
PAINT GREEN (-6345 3957);
DISPLAY INVISIBLE (-6345 3957);
FORCEPROP 1 LAST PATH I61
J 0
(-6225 4000);
DISPLAY 0.872340 (-6225 4000);
PAINT AQUA (-6225 4000);
DISPLAY INVISIBLE (-6225 4000);
FORCEPROP 2 LAST CDS_LIB mstr_symbols
J 0
(-6300 4000);
PAINT ORANGE (-6300 4000);
DISPLAY INVISIBLE (-6300 4000);
FORCEPROP 1 LAST SIZE 1B
J 0
(-6225 3950);
DISPLAY 1.170213 (-6225 3950);
PAINT AQUA (-6225 3950);
DISPLAY INVISIBLE (-6225 3950);
FORCEPROP 1 LAST VOLTAGE 0
J 0
(-6300 4000);
PAINT SKYBLUE (-6300 4000);
DISPLAY INVISIBLE (-6300 4000);
FORCEPROP 2 LAST ROOM PVCCIN_CPU0_VR
J 0
(-6875 4075);
DISPLAY 1.361702 (-6875 4075);
PAINT ORANGE (-6875 4075);
DISPLAY INVISIBLE (-6875 4075);
FORCEADD CAP..1
(-5550 2075);
FORCEPROP 1 LAST MATERIAL X7R
J 0
(-5900 1950);
DISPLAY 0.617021 (-5900 1950);
PAINT SKYBLUE (-5900 1950);
FORCEPROP 1 LAST VOLTAGE 50V
J 0
(-6050 1950);
DISPLAY 0.617021 (-6050 1950);
PAINT SKYBLUE (-6050 1950);
FORCEPROP 1 LAST PACK_TYPE 0402LF
J 0
(-5775 1950);
DISPLAY 0.617021 (-5775 1950);
PAINT SKYBLUE (-5775 1950);
FORCEPROP 1 LASTPIN (-5550 1975) $PN 2
J 0
(-5540 1955);
DISPLAY 0.617021 (-5540 1955);
PAINT ORANGE (-5540 1955);
FORCEPROP 1 LAST TOLERANCE 10%
J 0
(-5725 2025);
DISPLAY 0.617021 (-5725 2025);
PAINT SKYBLUE (-5725 2025);
FORCEPROP 1 LAST VALUE 220PF
J 0
(-5925 2025);
DISPLAY 0.617021 (-5925 2025);
PAINT SKYBLUE (-5925 2025);
FORCEPROP 1 LAST PART_NUMBER A36096-050
J 0
(-5925 2075);
DISPLAY 0.617021 (-5925 2075);
PAINT BLUE (-5925 2075);
FORCEPROP 1 LAST LOCATION C4D29
J 0
(-5800 2125);
DISPLAY 0.617021 (-5800 2125);
PAINT AQUA (-5800 2125);
FORCEPROP 1 LASTPIN (-5550 2175) $PN 1
J 0
(-5540 2155);
DISPLAY 0.617021 (-5540 2155);
PAINT ORANGE (-5540 2155);
FORCEPROP 2 LAST ROOM PVCCIN_CPU0_VR
J 0
(-5800 2175);
DISPLAY 1.361702 (-5800 2175);
PAINT ORANGE (-5800 2175);
DISPLAY INVISIBLE (-5800 2175);
FORCEPROP 2 LAST CDS_LOCATION C4D29
J 0
(-5800 2125);
DISPLAY 0.617021 (-5800 2125);
PAINT AQUA (-5800 2125);
DISPLAY INVISIBLE (-5800 2125);
FORCEPROP 2 LAST CDS_LIB mstr_discrete
J 0
(-5550 2075);
PAINT ORANGE (-5550 2075);
DISPLAY INVISIBLE (-5550 2075);
FORCEPROP 1 LAST PATH I64
J 0
(-5500 2225);
DISPLAY 0.978723 (-5500 2225);
PAINT WHITE (-5500 2225);
DISPLAY INVISIBLE (-5500 2225);
FORCEPROP 2 LAST SEC 1
J 0
(-5500 2275);
DISPLAY 0.680851 (-5500 2275);
PAINT MONO (-5500 2275);
DISPLAY INVISIBLE (-5500 2275);
FORCEPROP 2 LAST SEC_TYPE 0402LF
J 0
(-5500 2275);
DISPLAY 1.021277 (-5500 2275);
PAINT ORANGE (-5500 2275);
DISPLAY INVISIBLE (-5500 2275);
FORCEPROP 2 LAST NO_XNET_CONNECTION 1
J 0
(-5500 2275);
PAINT MONO (-5500 2275);
DISPLAY INVISIBLE (-5500 2275);
FORCEADD CAP..1
(-5450 1275);
FORCEPROP 1 LASTPIN (-5450 1175) $PN 2
J 0
(-5440 1155);
DISPLAY 0.617021 (-5440 1155);
PAINT ORANGE (-5440 1155);
FORCEPROP 1 LASTPIN (-5450 1375) $PN 1
J 0
(-5440 1355);
DISPLAY 0.617021 (-5440 1355);
PAINT ORANGE (-5440 1355);
FORCEPROP 1 LAST VOLTAGE 50V
J 0
(-5400 1275);
DISPLAY 0.617021 (-5400 1275);
PAINT SKYBLUE (-5400 1275);
FORCEPROP 1 LAST PACK_TYPE 0402LF
J 0
(-5400 1175);
DISPLAY 0.617021 (-5400 1175);
PAINT SKYBLUE (-5400 1175);
FORCEPROP 1 LAST VALUE 220PF
J 0
(-5400 1325);
DISPLAY 0.617021 (-5400 1325);
PAINT SKYBLUE (-5400 1325);
FORCEPROP 1 LAST LOCATION C4D17
J 0
(-5400 1375);
DISPLAY 0.617021 (-5400 1375);
PAINT AQUA (-5400 1375);
FORCEPROP 1 LAST MATERIAL X7R
J 0
(-5275 1275);
DISPLAY 0.617021 (-5275 1275);
PAINT SKYBLUE (-5275 1275);
FORCEPROP 1 LAST TOLERANCE 10%
J 0
(-5225 1325);
DISPLAY 0.617021 (-5225 1325);
PAINT SKYBLUE (-5225 1325);
FORCEPROP 1 LAST PART_NUMBER A36096-050
J 0
(-5400 1225);
DISPLAY 0.617021 (-5400 1225);
PAINT BLUE (-5400 1225);
FORCEPROP 2 LAST CDS_LIB mstr_discrete
J 0
(-5450 1275);
PAINT ORANGE (-5450 1275);
DISPLAY INVISIBLE (-5450 1275);
FORCEPROP 2 LAST ROOM PVCCIN_CPU0_VR
J 0
(-5400 1425);
DISPLAY 1.361702 (-5400 1425);
PAINT ORANGE (-5400 1425);
DISPLAY INVISIBLE (-5400 1425);
FORCEPROP 1 LAST PATH I66
J 0
(-5400 1425);
DISPLAY 0.978723 (-5400 1425);
PAINT WHITE (-5400 1425);
DISPLAY INVISIBLE (-5400 1425);
FORCEPROP 2 LAST CDS_LOCATION C4D17
J 0
(-5400 1375);
DISPLAY 0.617021 (-5400 1375);
PAINT AQUA (-5400 1375);
DISPLAY INVISIBLE (-5400 1375);
FORCEPROP 2 LAST SEC 1
J 0
(-5400 1475);
DISPLAY 0.680851 (-5400 1475);
PAINT MONO (-5400 1475);
DISPLAY INVISIBLE (-5400 1475);
FORCEPROP 2 LAST SEC_TYPE 0402LF
J 0
(-5400 1475);
DISPLAY 1.021277 (-5400 1475);
PAINT ORANGE (-5400 1475);
DISPLAY INVISIBLE (-5400 1475);
FORCEADD GND..1
(-5450 1025);
FORCEPROP 3 LASTPIN (-5450 1075) SIG_NAME GND\g
J 0
(-5440 1085);
DISPLAY 0.659574 (-5440 1085);
PAINT MONO (-5440 1085);
DISPLAY INVISIBLE (-5440 1085);
FORCEPROP 1 LAST HDL_POWER GND
J 0
(-5450 1175);
DISPLAY 1.170213 (-5450 1175);
PAINT GREEN (-5450 1175);
DISPLAY INVISIBLE (-5450 1175);
FORCEPROP 1 LAST BODY_TYPE PLUMBING
J 0
(-5495 982);
DISPLAY 0.340426 (-5495 982);
PAINT GREEN (-5495 982);
DISPLAY INVISIBLE (-5495 982);
FORCEPROP 1 LAST SIZE 1B
J 0
(-5375 975);
DISPLAY 1.170213 (-5375 975);
PAINT AQUA (-5375 975);
DISPLAY INVISIBLE (-5375 975);
FORCEPROP 2 LAST ROOM PVCCIN_CPU0_VR
J 0
(-6025 1100);
DISPLAY 1.361702 (-6025 1100);
PAINT ORANGE (-6025 1100);
DISPLAY INVISIBLE (-6025 1100);
FORCEPROP 1 LAST VOLTAGE 0
J 0
(-5450 1025);
PAINT SKYBLUE (-5450 1025);
DISPLAY INVISIBLE (-5450 1025);
FORCEPROP 2 LAST CDS_LIB mstr_symbols
J 0
(-5450 1025);
PAINT ORANGE (-5450 1025);
DISPLAY INVISIBLE (-5450 1025);
FORCEPROP 1 LAST PATH I67
J 0
(-5375 1025);
DISPLAY 0.872340 (-5375 1025);
PAINT AQUA (-5375 1025);
DISPLAY INVISIBLE (-5375 1025);
FORCEADD CAP..1
R 2
(-5125 1000);
FORCEPROP 1 LAST PART_NUMBER A36096-050
J 2
(-5175 950);
DISPLAY 0.617021 (-5175 950);
PAINT BLUE (-5175 950);
FORCEPROP 1 LASTPIN (-5125 900) $PN 2
J 2
(-5135 880);
DISPLAY 0.617021 (-5135 880);
PAINT ORANGE (-5135 880);
FORCEPROP 1 LAST PACK_TYPE 0402LF
J 2
(-5175 900);
DISPLAY 0.617021 (-5175 900);
PAINT SKYBLUE (-5175 900);
FORCEPROP 1 LAST MATERIAL X7R
J 2
(-5300 1000);
DISPLAY 0.617021 (-5300 1000);
PAINT SKYBLUE (-5300 1000);
FORCEPROP 1 LAST VOLTAGE 50V
J 2
(-5175 1000);
DISPLAY 0.617021 (-5175 1000);
PAINT SKYBLUE (-5175 1000);
FORCEPROP 1 LAST TOLERANCE 10%
J 2
(-5350 1050);
DISPLAY 0.617021 (-5350 1050);
PAINT SKYBLUE (-5350 1050);
FORCEPROP 1 LAST VALUE 220PF
J 2
(-5175 1050);
DISPLAY 0.617021 (-5175 1050);
PAINT SKYBLUE (-5175 1050);
FORCEPROP 1 LAST LOCATION C4D18
J 2
(-5175 1100);
DISPLAY 0.617021 (-5175 1100);
PAINT AQUA (-5175 1100);
FORCEPROP 1 LASTPIN (-5125 1100) $PN 1
J 2
(-5135 1080);
DISPLAY 0.617021 (-5135 1080);
PAINT ORANGE (-5135 1080);
FORCEPROP 2 LAST CDS_LIB mstr_discrete
J 2
(-5125 1000);
PAINT ORANGE (-5125 1000);
DISPLAY INVISIBLE (-5125 1000);
FORCEPROP 2 LAST SEC_TYPE 0402LF
J 0
(-5175 1200);
DISPLAY 1.021277 (-5175 1200);
PAINT ORANGE (-5175 1200);
DISPLAY INVISIBLE (-5175 1200);
FORCEPROP 1 LAST PATH I68
J 2
(-5175 1150);
DISPLAY 0.978723 (-5175 1150);
PAINT WHITE (-5175 1150);
DISPLAY INVISIBLE (-5175 1150);
FORCEPROP 2 LAST CDS_LOCATION C4D18
J 2
(-5175 1100);
DISPLAY 0.617021 (-5175 1100);
PAINT AQUA (-5175 1100);
DISPLAY INVISIBLE (-5175 1100);
FORCEPROP 2 LAST SEC 1
J 0
(-5175 1200);
DISPLAY 0.680851 (-5175 1200);
PAINT MONO (-5175 1200);
DISPLAY INVISIBLE (-5175 1200);
FORCEPROP 2 LAST ROOM PVCCIN_CPU0_VR
J 0
(-5175 1150);
DISPLAY 1.361702 (-5175 1150);
PAINT ORANGE (-5175 1150);
DISPLAY INVISIBLE (-5175 1150);
FORCEADD GND..1
(-5125 775);
FORCEPROP 3 LASTPIN (-5125 825) SIG_NAME GND\g
J 0
(-5115 835);
DISPLAY 0.659574 (-5115 835);
PAINT MONO (-5115 835);
DISPLAY INVISIBLE (-5115 835);
FORCEPROP 1 LAST HDL_POWER GND
J 0
(-5125 925);
DISPLAY 1.170213 (-5125 925);
PAINT GREEN (-5125 925);
DISPLAY INVISIBLE (-5125 925);
FORCEPROP 1 LAST BODY_TYPE PLUMBING
J 0
(-5170 732);
DISPLAY 0.340426 (-5170 732);
PAINT GREEN (-5170 732);
DISPLAY INVISIBLE (-5170 732);
FORCEPROP 2 LAST ROOM PVCCIN_CPU0_VR
J 0
(-5700 850);
DISPLAY 1.361702 (-5700 850);
PAINT ORANGE (-5700 850);
DISPLAY INVISIBLE (-5700 850);
FORCEPROP 2 LAST CDS_LIB mstr_symbols
J 0
(-5125 775);
PAINT ORANGE (-5125 775);
DISPLAY INVISIBLE (-5125 775);
FORCEPROP 1 LAST VOLTAGE 0
J 0
(-5125 775);
PAINT SKYBLUE (-5125 775);
DISPLAY INVISIBLE (-5125 775);
FORCEPROP 1 LAST PATH I69
J 0
(-5050 775);
DISPLAY 0.872340 (-5050 775);
PAINT AQUA (-5050 775);
DISPLAY INVISIBLE (-5050 775);
FORCEPROP 1 LAST SIZE 1B
J 0
(-5050 725);
DISPLAY 1.170213 (-5050 725);
PAINT AQUA (-5050 725);
DISPLAY INVISIBLE (-5050 725);
FORCEADD OFFPAGE..2
(-1050 2375);
FORCEPROP 2 LAST $XR0 203 
J 0
(-861 2375);
DISPLAY 0.638298 (-861 2375);
PAINT MONO (-861 2375);
FORCEPROP 1 LAST COMMENT_BODY TRUE
J 0
(-1095 2280);
DISPLAY 1.170213 (-1095 2280);
PAINT GREEN (-1095 2280);
DISPLAY INVISIBLE (-1095 2280);
FORCEPROP 1 LAST OFFPAGE TRUE
J 0
(-725 2250);
DISPLAY 1.170213 (-725 2250);
PAINT GREEN (-725 2250);
DISPLAY INVISIBLE (-725 2250);
FORCEPROP 2 LAST ROOM PVCCIN_CPU0_VR
J 0
(-1475 2450);
DISPLAY 1.361702 (-1475 2450);
PAINT ORANGE (-1475 2450);
DISPLAY INVISIBLE (-1475 2450);
FORCEPROP 2 LAST CDS_LIB mstr_standard
J 0
(-1050 2375);
PAINT ORANGE (-1050 2375);
DISPLAY INVISIBLE (-1050 2375);
FORCEPROP 2 LAST PATH I7
J 0
(-875 2450);
DISPLAY 1.021277 (-875 2450);
PAINT ORANGE (-875 2450);
DISPLAY INVISIBLE (-875 2450);
FORCEADD CAP..1
(-6450 2375);
FORCEPROP 1 LASTPIN (-6450 2275) $PN 2
J 0
(-6440 2255);
DISPLAY 0.617021 (-6440 2255);
PAINT ORANGE (-6440 2255);
FORCEPROP 1 LASTPIN (-6450 2475) $PN 1
J 0
(-6440 2455);
DISPLAY 0.617021 (-6440 2455);
PAINT ORANGE (-6440 2455);
FORCEPROP 1 LAST VOLTAGE 50V
J 0
(-6400 2375);
DISPLAY 0.617021 (-6400 2375);
PAINT SKYBLUE (-6400 2375);
FORCEPROP 1 LAST PACK_TYPE 0402LF
J 0
(-6400 2275);
DISPLAY 0.617021 (-6400 2275);
PAINT SKYBLUE (-6400 2275);
FORCEPROP 1 LAST VALUE 220PF
J 0
(-6400 2425);
DISPLAY 0.617021 (-6400 2425);
PAINT SKYBLUE (-6400 2425);
FORCEPROP 1 LAST LOCATION C4D45
J 0
(-6400 2475);
DISPLAY 0.617021 (-6400 2475);
PAINT AQUA (-6400 2475);
FORCEPROP 1 LAST MATERIAL X7R
J 0
(-6275 2375);
DISPLAY 0.617021 (-6275 2375);
PAINT SKYBLUE (-6275 2375);
FORCEPROP 2 LAST NO_XNET_CONNECTION 1
J 0
(-6400 2575);
PAINT MONO (-6400 2575);
FORCEPROP 1 LAST TOLERANCE 10%
J 0
(-6225 2425);
DISPLAY 0.617021 (-6225 2425);
PAINT SKYBLUE (-6225 2425);
FORCEPROP 1 LAST PART_NUMBER A36096-050
J 0
(-6400 2325);
DISPLAY 0.617021 (-6400 2325);
PAINT BLUE (-6400 2325);
FORCEPROP 2 LAST CDS_LIB mstr_discrete
J 0
(-6450 2375);
PAINT ORANGE (-6450 2375);
DISPLAY INVISIBLE (-6450 2375);
FORCEPROP 2 LAST CDS_LOCATION C4D45
J 0
(-6400 2475);
DISPLAY 0.617021 (-6400 2475);
PAINT AQUA (-6400 2475);
DISPLAY INVISIBLE (-6400 2475);
FORCEPROP 2 LAST ROOM PVCCIN_CPU0_VR
J 0
(-6400 2525);
DISPLAY 1.361702 (-6400 2525);
PAINT ORANGE (-6400 2525);
DISPLAY INVISIBLE (-6400 2525);
FORCEPROP 1 LAST PATH I70
J 0
(-6400 2525);
DISPLAY 0.978723 (-6400 2525);
PAINT WHITE (-6400 2525);
DISPLAY INVISIBLE (-6400 2525);
FORCEPROP 2 LAST SEC 1
J 0
(-6400 2575);
DISPLAY 0.680851 (-6400 2575);
PAINT MONO (-6400 2575);
DISPLAY INVISIBLE (-6400 2575);
FORCEPROP 2 LAST SEC_TYPE 0402LF
J 0
(-6400 2575);
DISPLAY 1.021277 (-6400 2575);
PAINT ORANGE (-6400 2575);
DISPLAY INVISIBLE (-6400 2575);
FORCEADD OFFPAGE..2
R 2
(-7375 4425);
FORCEPROP 2 LAST $XR0 201 
J 0
(-7630 4425);
DISPLAY 0.638298 (-7630 4425);
PAINT MONO (-7630 4425);
FORCEPROP 1 LAST COMMENT_BODY TRUE
J 2
(-7330 4330);
DISPLAY 1.170213 (-7330 4330);
PAINT GREEN (-7330 4330);
DISPLAY INVISIBLE (-7330 4330);
FORCEPROP 1 LAST OFFPAGE TRUE
J 2
(-7700 4300);
DISPLAY 1.170213 (-7700 4300);
PAINT GREEN (-7700 4300);
DISPLAY INVISIBLE (-7700 4300);
FORCEPROP 2 LAST ROOM PVCCIN_CPU0_VR
J 0
(-7925 4500);
DISPLAY 1.361702 (-7925 4500);
PAINT ORANGE (-7925 4500);
DISPLAY INVISIBLE (-7925 4500);
FORCEPROP 2 LAST PATH I73
J 0
(-7325 4500);
DISPLAY 1.021277 (-7325 4500);
PAINT ORANGE (-7325 4500);
DISPLAY INVISIBLE (-7325 4500);
FORCEPROP 2 LAST CDS_LIB mstr_standard
J 2
(-7375 4425);
PAINT ORANGE (-7375 4425);
DISPLAY INVISIBLE (-7375 4425);
FORCEADD OFFPAGE..1
(-7400 3950);
FORCEPROP 2 LAST $XR0 21 
J 0
(-7651 3950);
DISPLAY 0.638298 (-7651 3950);
PAINT MONO (-7651 3950);
FORCEPROP 2 LAST $XR1 194 
J 0
(-7771 3950);
DISPLAY 0.638298 (-7771 3950);
PAINT MONO (-7771 3950);
FORCEPROP 2 LAST $XR2 211 
J 0
(-7891 3950);
DISPLAY 0.638298 (-7891 3950);
PAINT MONO (-7891 3950);
FORCEPROP 1 LAST COMMENT_BODY TRUE
J 0
(-7275 3850);
DISPLAY 1.170213 (-7275 3850);
PAINT GREEN (-7275 3850);
DISPLAY INVISIBLE (-7275 3850);
FORCEPROP 1 LAST OFFPAGE TRUE
J 0
(-7075 3825);
DISPLAY 1.170213 (-7075 3825);
PAINT GREEN (-7075 3825);
DISPLAY INVISIBLE (-7075 3825);
FORCEPROP 2 LAST ROOM PVCCIN_CPU0_VR
J 0
(-7950 4025);
DISPLAY 1.361702 (-7950 4025);
PAINT ORANGE (-7950 4025);
DISPLAY INVISIBLE (-7950 4025);
FORCEPROP 2 LAST CDS_LIB mstr_standard
J 0
(-7400 3950);
PAINT ORANGE (-7400 3950);
DISPLAY INVISIBLE (-7400 3950);
FORCEPROP 2 LAST PATH I74
J 0
(-7350 4025);
DISPLAY 1.021277 (-7350 4025);
PAINT ORANGE (-7350 4025);
DISPLAY INVISIBLE (-7350 4025);
FORCEADD OFFPAGE..1
(-7400 3175);
FORCEPROP 2 LAST $XR0 202 
J 0
(-7682 3175);
DISPLAY 0.638298 (-7682 3175);
PAINT MONO (-7682 3175);
FORCEPROP 1 LAST COMMENT_BODY TRUE
J 0
(-7275 3075);
DISPLAY 1.170213 (-7275 3075);
PAINT GREEN (-7275 3075);
DISPLAY INVISIBLE (-7275 3075);
FORCEPROP 1 LAST OFFPAGE TRUE
J 0
(-7075 3050);
DISPLAY 1.170213 (-7075 3050);
PAINT GREEN (-7075 3050);
DISPLAY INVISIBLE (-7075 3050);
FORCEPROP 2 LAST ROOM PVCCIN_CPU0_VR
J 0
(-7950 3250);
DISPLAY 1.361702 (-7950 3250);
PAINT ORANGE (-7950 3250);
DISPLAY INVISIBLE (-7950 3250);
FORCEPROP 2 LAST CDS_LIB mstr_standard
J 0
(-7400 3175);
PAINT ORANGE (-7400 3175);
DISPLAY INVISIBLE (-7400 3175);
FORCEPROP 2 LAST PATH I75
J 0
(-7350 3250);
DISPLAY 1.021277 (-7350 3250);
PAINT ORANGE (-7350 3250);
DISPLAY INVISIBLE (-7350 3250);
FORCEADD OFFPAGE..1
(-7400 3125);
FORCEPROP 2 LAST $XR0 202 
J 0
(-7682 3125);
DISPLAY 0.638298 (-7682 3125);
PAINT MONO (-7682 3125);
FORCEPROP 1 LAST COMMENT_BODY TRUE
J 0
(-7275 3025);
DISPLAY 1.170213 (-7275 3025);
PAINT GREEN (-7275 3025);
DISPLAY INVISIBLE (-7275 3025);
FORCEPROP 1 LAST OFFPAGE TRUE
J 0
(-7075 3000);
DISPLAY 1.170213 (-7075 3000);
PAINT GREEN (-7075 3000);
DISPLAY INVISIBLE (-7075 3000);
FORCEPROP 2 LAST ROOM PVCCIN_CPU0_VR
J 0
(-7950 3200);
DISPLAY 1.361702 (-7950 3200);
PAINT ORANGE (-7950 3200);
DISPLAY INVISIBLE (-7950 3200);
FORCEPROP 2 LAST CDS_LIB mstr_standard
J 0
(-7400 3125);
PAINT ORANGE (-7400 3125);
DISPLAY INVISIBLE (-7400 3125);
FORCEPROP 2 LAST PATH I76
J 0
(-7350 3200);
DISPLAY 1.021277 (-7350 3200);
PAINT ORANGE (-7350 3200);
DISPLAY INVISIBLE (-7350 3200);
FORCEADD OFFPAGE..1
(-7400 3075);
FORCEPROP 2 LAST $XR0 203 
J 0
(-7682 3075);
DISPLAY 0.638298 (-7682 3075);
PAINT MONO (-7682 3075);
FORCEPROP 1 LAST COMMENT_BODY TRUE
J 0
(-7275 2975);
DISPLAY 1.170213 (-7275 2975);
PAINT GREEN (-7275 2975);
DISPLAY INVISIBLE (-7275 2975);
FORCEPROP 1 LAST OFFPAGE TRUE
J 0
(-7075 2950);
DISPLAY 1.170213 (-7075 2950);
PAINT GREEN (-7075 2950);
DISPLAY INVISIBLE (-7075 2950);
FORCEPROP 2 LAST ROOM PVCCIN_CPU0_VR
J 0
(-7950 3150);
DISPLAY 1.361702 (-7950 3150);
PAINT ORANGE (-7950 3150);
DISPLAY INVISIBLE (-7950 3150);
FORCEPROP 2 LAST CDS_LIB mstr_standard
J 0
(-7400 3075);
PAINT ORANGE (-7400 3075);
DISPLAY INVISIBLE (-7400 3075);
FORCEPROP 2 LAST PATH I77
J 0
(-7350 3150);
DISPLAY 1.021277 (-7350 3150);
PAINT ORANGE (-7350 3150);
DISPLAY INVISIBLE (-7350 3150);
FORCEADD OFFPAGE..1
(-7400 2875);
FORCEPROP 2 LAST $XR0 202 
J 0
(-7682 2875);
DISPLAY 0.638298 (-7682 2875);
PAINT MONO (-7682 2875);
FORCEPROP 1 LAST COMMENT_BODY TRUE
J 0
(-7275 2775);
DISPLAY 1.170213 (-7275 2775);
PAINT GREEN (-7275 2775);
DISPLAY INVISIBLE (-7275 2775);
FORCEPROP 1 LAST OFFPAGE TRUE
J 0
(-7075 2750);
DISPLAY 1.170213 (-7075 2750);
PAINT GREEN (-7075 2750);
DISPLAY INVISIBLE (-7075 2750);
FORCEPROP 2 LAST ROOM PVCCIN_CPU0_VR
J 0
(-7950 2950);
DISPLAY 1.361702 (-7950 2950);
PAINT ORANGE (-7950 2950);
DISPLAY INVISIBLE (-7950 2950);
FORCEPROP 2 LAST CDS_LIB mstr_standard
J 0
(-7400 2875);
PAINT ORANGE (-7400 2875);
DISPLAY INVISIBLE (-7400 2875);
FORCEPROP 2 LAST PATH I78
J 0
(-7350 2950);
DISPLAY 1.021277 (-7350 2950);
PAINT ORANGE (-7350 2950);
DISPLAY INVISIBLE (-7350 2950);
FORCEADD OFFPAGE..1
(-7400 3025);
FORCEPROP 2 LAST $XR0 203 
J 0
(-7682 3025);
DISPLAY 0.638298 (-7682 3025);
PAINT MONO (-7682 3025);
FORCEPROP 1 LAST COMMENT_BODY TRUE
J 0
(-7275 2925);
DISPLAY 1.170213 (-7275 2925);
PAINT GREEN (-7275 2925);
DISPLAY INVISIBLE (-7275 2925);
FORCEPROP 1 LAST OFFPAGE TRUE
J 0
(-7075 2900);
DISPLAY 1.170213 (-7075 2900);
PAINT GREEN (-7075 2900);
DISPLAY INVISIBLE (-7075 2900);
FORCEPROP 2 LAST CDS_LIB mstr_standard
J 0
(-7400 3025);
PAINT ORANGE (-7400 3025);
DISPLAY INVISIBLE (-7400 3025);
FORCEPROP 2 LAST ROOM PVCCIN_CPU0_VR
J 0
(-7950 3100);
DISPLAY 1.361702 (-7950 3100);
PAINT ORANGE (-7950 3100);
DISPLAY INVISIBLE (-7950 3100);
FORCEPROP 2 LAST PATH I79
J 0
(-7350 3100);
DISPLAY 1.021277 (-7350 3100);
PAINT ORANGE (-7350 3100);
DISPLAY INVISIBLE (-7350 3100);
FORCEADD OFFPAGE..2
(-1050 2525);
FORCEPROP 2 LAST $XR0 205 
J 0
(-861 2525);
DISPLAY 0.638298 (-861 2525);
PAINT MONO (-861 2525);
FORCEPROP 1 LAST COMMENT_BODY TRUE
J 0
(-1095 2430);
DISPLAY 1.170213 (-1095 2430);
PAINT GREEN (-1095 2430);
DISPLAY INVISIBLE (-1095 2430);
FORCEPROP 1 LAST OFFPAGE TRUE
J 0
(-725 2400);
DISPLAY 1.170213 (-725 2400);
PAINT GREEN (-725 2400);
DISPLAY INVISIBLE (-725 2400);
FORCEPROP 2 LAST CDS_LIB mstr_standard
J 0
(-1050 2525);
PAINT ORANGE (-1050 2525);
DISPLAY INVISIBLE (-1050 2525);
FORCEPROP 2 LAST ROOM PVCCIN_CPU0_VR
J 0
(-1475 2600);
DISPLAY 1.361702 (-1475 2600);
PAINT ORANGE (-1475 2600);
DISPLAY INVISIBLE (-1475 2600);
FORCEPROP 2 LAST PATH I8
J 0
(-875 2600);
DISPLAY 1.021277 (-875 2600);
PAINT ORANGE (-875 2600);
DISPLAY INVISIBLE (-875 2600);
FORCEADD OFFPAGE..1
(-7400 2975);
FORCEPROP 2 LAST $XR0 204 
J 0
(-7682 2975);
DISPLAY 0.638298 (-7682 2975);
PAINT MONO (-7682 2975);
FORCEPROP 1 LAST COMMENT_BODY TRUE
J 0
(-7275 2875);
DISPLAY 1.170213 (-7275 2875);
PAINT GREEN (-7275 2875);
DISPLAY INVISIBLE (-7275 2875);
FORCEPROP 1 LAST OFFPAGE TRUE
J 0
(-7075 2850);
DISPLAY 1.170213 (-7075 2850);
PAINT GREEN (-7075 2850);
DISPLAY INVISIBLE (-7075 2850);
FORCEPROP 2 LAST CDS_LIB mstr_standard
J 0
(-7400 2975);
PAINT ORANGE (-7400 2975);
DISPLAY INVISIBLE (-7400 2975);
FORCEPROP 2 LAST PATH I80
J 0
(-7350 3050);
DISPLAY 1.021277 (-7350 3050);
PAINT ORANGE (-7350 3050);
DISPLAY INVISIBLE (-7350 3050);
FORCEPROP 2 LAST ROOM PVCCIN_CPU0_VR
J 0
(-7950 3050);
DISPLAY 1.361702 (-7950 3050);
PAINT ORANGE (-7950 3050);
DISPLAY INVISIBLE (-7950 3050);
FORCEADD OFFPAGE..1
(-7400 2825);
FORCEPROP 2 LAST $XR0 202 
J 0
(-7682 2825);
DISPLAY 0.638298 (-7682 2825);
PAINT MONO (-7682 2825);
FORCEPROP 1 LAST COMMENT_BODY TRUE
J 0
(-7275 2725);
DISPLAY 1.170213 (-7275 2725);
PAINT GREEN (-7275 2725);
DISPLAY INVISIBLE (-7275 2725);
FORCEPROP 1 LAST OFFPAGE TRUE
J 0
(-7075 2700);
DISPLAY 1.170213 (-7075 2700);
PAINT GREEN (-7075 2700);
DISPLAY INVISIBLE (-7075 2700);
FORCEPROP 2 LAST ROOM PVCCIN_CPU0_VR
J 0
(-7950 2900);
DISPLAY 1.361702 (-7950 2900);
PAINT ORANGE (-7950 2900);
DISPLAY INVISIBLE (-7950 2900);
FORCEPROP 2 LAST CDS_LIB mstr_standard
J 0
(-7400 2825);
PAINT ORANGE (-7400 2825);
DISPLAY INVISIBLE (-7400 2825);
FORCEPROP 2 LAST PATH I82
J 0
(-7350 2900);
DISPLAY 1.021277 (-7350 2900);
PAINT ORANGE (-7350 2900);
DISPLAY INVISIBLE (-7350 2900);
FORCEADD OFFPAGE..1
(-7400 2775);
FORCEPROP 2 LAST $XR0 203 
J 0
(-7682 2775);
DISPLAY 0.638298 (-7682 2775);
PAINT MONO (-7682 2775);
FORCEPROP 1 LAST COMMENT_BODY TRUE
J 0
(-7275 2675);
DISPLAY 1.170213 (-7275 2675);
PAINT GREEN (-7275 2675);
DISPLAY INVISIBLE (-7275 2675);
FORCEPROP 1 LAST OFFPAGE TRUE
J 0
(-7075 2650);
DISPLAY 0.936170 (-7075 2650);
PAINT GREEN (-7075 2650);
DISPLAY INVISIBLE (-7075 2650);
FORCEPROP 2 LAST ROOM PVCCIN_CPU0_VR
J 0
(-7950 2850);
DISPLAY 1.361702 (-7950 2850);
PAINT ORANGE (-7950 2850);
DISPLAY INVISIBLE (-7950 2850);
FORCEPROP 2 LAST CDS_LIB mstr_standard
J 0
(-7400 2775);
PAINT ORANGE (-7400 2775);
DISPLAY INVISIBLE (-7400 2775);
FORCEPROP 2 LAST PATH I83
J 0
(-7350 2850);
DISPLAY 1.021277 (-7350 2850);
PAINT ORANGE (-7350 2850);
DISPLAY INVISIBLE (-7350 2850);
FORCEADD OFFPAGE..1
(-7400 2725);
FORCEPROP 2 LAST $XR0 203 
J 0
(-7682 2725);
DISPLAY 0.638298 (-7682 2725);
PAINT MONO (-7682 2725);
FORCEPROP 1 LAST COMMENT_BODY TRUE
J 0
(-7275 2625);
DISPLAY 1.170213 (-7275 2625);
PAINT GREEN (-7275 2625);
DISPLAY INVISIBLE (-7275 2625);
FORCEPROP 1 LAST OFFPAGE TRUE
J 0
(-7075 2600);
DISPLAY 1.170213 (-7075 2600);
PAINT GREEN (-7075 2600);
DISPLAY INVISIBLE (-7075 2600);
FORCEPROP 2 LAST ROOM PVCCIN_CPU0_VR
J 0
(-7950 2800);
DISPLAY 1.361702 (-7950 2800);
PAINT ORANGE (-7950 2800);
DISPLAY INVISIBLE (-7950 2800);
FORCEPROP 2 LAST CDS_LIB mstr_standard
J 0
(-7400 2725);
PAINT ORANGE (-7400 2725);
DISPLAY INVISIBLE (-7400 2725);
FORCEPROP 2 LAST PATH I84
J 0
(-7350 2800);
DISPLAY 1.021277 (-7350 2800);
PAINT ORANGE (-7350 2800);
DISPLAY INVISIBLE (-7350 2800);
FORCEADD OFFPAGE..1
(-7400 2675);
FORCEPROP 2 LAST $XR0 204 
J 0
(-7682 2675);
DISPLAY 0.638298 (-7682 2675);
PAINT MONO (-7682 2675);
FORCEPROP 1 LAST COMMENT_BODY TRUE
J 0
(-7275 2575);
DISPLAY 1.170213 (-7275 2575);
PAINT GREEN (-7275 2575);
DISPLAY INVISIBLE (-7275 2575);
FORCEPROP 1 LAST OFFPAGE TRUE
J 0
(-7075 2550);
DISPLAY 1.170213 (-7075 2550);
PAINT GREEN (-7075 2550);
DISPLAY INVISIBLE (-7075 2550);
FORCEPROP 2 LAST ROOM PVCCIN_CPU0_VR
J 0
(-7950 2750);
DISPLAY 1.361702 (-7950 2750);
PAINT ORANGE (-7950 2750);
DISPLAY INVISIBLE (-7950 2750);
FORCEPROP 2 LAST CDS_LIB mstr_standard
J 0
(-7400 2675);
PAINT ORANGE (-7400 2675);
DISPLAY INVISIBLE (-7400 2675);
FORCEPROP 2 LAST PATH I85
J 0
(-7350 2750);
DISPLAY 1.021277 (-7350 2750);
PAINT ORANGE (-7350 2750);
DISPLAY INVISIBLE (-7350 2750);
FORCEADD OFFPAGE..1
(-7375 2525);
FORCEPROP 2 LAST $XR0 204 
J 0
(-7657 2525);
DISPLAY 0.638298 (-7657 2525);
PAINT MONO (-7657 2525);
FORCEPROP 1 LAST COMMENT_BODY TRUE
J 0
(-7250 2425);
DISPLAY 1.170213 (-7250 2425);
PAINT GREEN (-7250 2425);
DISPLAY INVISIBLE (-7250 2425);
FORCEPROP 1 LAST OFFPAGE TRUE
J 0
(-7050 2400);
DISPLAY 1.170213 (-7050 2400);
PAINT GREEN (-7050 2400);
DISPLAY INVISIBLE (-7050 2400);
FORCEPROP 2 LAST ROOM PVCCIN_CPU0_VR
J 0
(-7925 2600);
DISPLAY 1.361702 (-7925 2600);
PAINT ORANGE (-7925 2600);
DISPLAY INVISIBLE (-7925 2600);
FORCEPROP 2 LAST CDS_LIB mstr_standard
J 0
(-7375 2525);
PAINT ORANGE (-7375 2525);
DISPLAY INVISIBLE (-7375 2525);
FORCEPROP 2 LAST PATH I87
J 0
(-7325 2600);
DISPLAY 1.021277 (-7325 2600);
PAINT ORANGE (-7325 2600);
DISPLAY INVISIBLE (-7325 2600);
FORCEADD OFFPAGE..1
(-7400 2250);
FORCEPROP 2 LAST $XR0 204 
J 0
(-7682 2250);
DISPLAY 0.638298 (-7682 2250);
PAINT MONO (-7682 2250);
FORCEPROP 1 LAST COMMENT_BODY TRUE
J 0
(-7275 2150);
DISPLAY 1.170213 (-7275 2150);
PAINT GREEN (-7275 2150);
DISPLAY INVISIBLE (-7275 2150);
FORCEPROP 1 LAST OFFPAGE TRUE
J 0
(-7075 2125);
DISPLAY 1.170213 (-7075 2125);
PAINT GREEN (-7075 2125);
DISPLAY INVISIBLE (-7075 2125);
FORCEPROP 2 LAST ROOM PVCCIN_CPU0_VR
J 0
(-7950 2325);
DISPLAY 1.361702 (-7950 2325);
PAINT ORANGE (-7950 2325);
DISPLAY INVISIBLE (-7950 2325);
FORCEPROP 2 LAST CDS_LIB mstr_standard
J 0
(-7400 2250);
PAINT ORANGE (-7400 2250);
DISPLAY INVISIBLE (-7400 2250);
FORCEPROP 2 LAST PATH I88
J 0
(-7350 2325);
DISPLAY 1.021277 (-7350 2325);
PAINT ORANGE (-7350 2325);
DISPLAY INVISIBLE (-7350 2325);
FORCEADD OFFPAGE..1
(-7400 2075);
FORCEPROP 2 LAST $XR0 205 
J 0
(-7682 2075);
DISPLAY 0.638298 (-7682 2075);
PAINT MONO (-7682 2075);
FORCEPROP 1 LAST COMMENT_BODY TRUE
J 0
(-7275 1975);
DISPLAY 1.170213 (-7275 1975);
PAINT GREEN (-7275 1975);
DISPLAY INVISIBLE (-7275 1975);
FORCEPROP 1 LAST OFFPAGE TRUE
J 0
(-7075 1950);
DISPLAY 1.170213 (-7075 1950);
PAINT GREEN (-7075 1950);
DISPLAY INVISIBLE (-7075 1950);
FORCEPROP 2 LAST ROOM PVCCIN_CPU0_VR
J 0
(-7950 2150);
DISPLAY 1.361702 (-7950 2150);
PAINT ORANGE (-7950 2150);
DISPLAY INVISIBLE (-7950 2150);
FORCEPROP 2 LAST CDS_LIB mstr_standard
J 0
(-7400 2075);
PAINT ORANGE (-7400 2075);
DISPLAY INVISIBLE (-7400 2075);
FORCEPROP 2 LAST PATH I89
J 0
(-7350 2150);
DISPLAY 1.021277 (-7350 2150);
PAINT ORANGE (-7350 2150);
DISPLAY INVISIBLE (-7350 2150);
FORCEADD OFFPAGE..2
(-1050 2475);
FORCEPROP 2 LAST $XR0 202 
J 0
(-861 2475);
DISPLAY 0.638298 (-861 2475);
PAINT MONO (-861 2475);
FORCEPROP 1 LAST COMMENT_BODY TRUE
J 0
(-1095 2380);
DISPLAY 1.170213 (-1095 2380);
PAINT GREEN (-1095 2380);
DISPLAY INVISIBLE (-1095 2380);
FORCEPROP 1 LAST OFFPAGE TRUE
J 0
(-725 2350);
DISPLAY 1.170213 (-725 2350);
PAINT GREEN (-725 2350);
DISPLAY INVISIBLE (-725 2350);
FORCEPROP 2 LAST CDS_LIB mstr_standard
J 0
(-1050 2475);
PAINT ORANGE (-1050 2475);
DISPLAY INVISIBLE (-1050 2475);
FORCEPROP 2 LAST ROOM PVCCIN_CPU0_VR
J 0
(-1475 2550);
DISPLAY 1.361702 (-1475 2550);
PAINT ORANGE (-1475 2550);
DISPLAY INVISIBLE (-1475 2550);
FORCEPROP 2 LAST PATH I9
J 0
(-875 2550);
DISPLAY 1.021277 (-875 2550);
PAINT ORANGE (-875 2550);
DISPLAY INVISIBLE (-875 2550);
FORCEADD OFFPAGE..1
(-7400 1925);
FORCEPROP 2 LAST $XR0 205 
J 0
(-7682 1925);
DISPLAY 0.638298 (-7682 1925);
PAINT MONO (-7682 1925);
FORCEPROP 1 LAST COMMENT_BODY TRUE
J 0
(-7275 1825);
DISPLAY 1.170213 (-7275 1825);
PAINT GREEN (-7275 1825);
DISPLAY INVISIBLE (-7275 1825);
FORCEPROP 1 LAST OFFPAGE TRUE
J 0
(-7075 1800);
DISPLAY 1.170213 (-7075 1800);
PAINT GREEN (-7075 1800);
DISPLAY INVISIBLE (-7075 1800);
FORCEPROP 2 LAST PATH I90
J 0
(-7350 2000);
DISPLAY 1.021277 (-7350 2000);
PAINT ORANGE (-7350 2000);
DISPLAY INVISIBLE (-7350 2000);
FORCEPROP 2 LAST CDS_LIB mstr_standard
J 0
(-7400 1925);
PAINT ORANGE (-7400 1925);
DISPLAY INVISIBLE (-7400 1925);
FORCEPROP 2 LAST ROOM PVCCIN_CPU0_VR
J 0
(-7950 2000);
DISPLAY 1.361702 (-7950 2000);
PAINT ORANGE (-7950 2000);
DISPLAY INVISIBLE (-7950 2000);
FORCEADD OFFPAGE..1
(-7400 1875);
FORCEPROP 2 LAST $XR0 202 
J 0
(-7682 1875);
DISPLAY 0.638298 (-7682 1875);
PAINT MONO (-7682 1875);
FORCEPROP 2 LAST $XR1 203 
J 0
(-7802 1875);
DISPLAY 0.638298 (-7802 1875);
PAINT MONO (-7802 1875);
FORCEPROP 2 LAST $XR2 204 
J 0
(-7922 1875);
DISPLAY 0.638298 (-7922 1875);
PAINT MONO (-7922 1875);
FORCEPROP 1 LAST COMMENT_BODY TRUE
J 0
(-7275 1775);
DISPLAY 1.170213 (-7275 1775);
PAINT GREEN (-7275 1775);
DISPLAY INVISIBLE (-7275 1775);
FORCEPROP 1 LAST OFFPAGE TRUE
J 0
(-7075 1750);
DISPLAY 1.170213 (-7075 1750);
PAINT GREEN (-7075 1750);
DISPLAY INVISIBLE (-7075 1750);
FORCEPROP 2 LAST ROOM PVCCIN_CPU0_VR
J 0
(-7950 1950);
DISPLAY 1.361702 (-7950 1950);
PAINT ORANGE (-7950 1950);
DISPLAY INVISIBLE (-7950 1950);
FORCEPROP 2 LAST CDS_LIB mstr_standard
J 0
(-7400 1875);
PAINT ORANGE (-7400 1875);
DISPLAY INVISIBLE (-7400 1875);
FORCEPROP 2 LAST PATH I91
J 0
(-7350 1950);
DISPLAY 1.021277 (-7350 1950);
PAINT ORANGE (-7350 1950);
DISPLAY INVISIBLE (-7350 1950);
FORCEADD OFFPAGE..1
(-7400 1825);
FORCEPROP 2 LAST $XR0 191 
J 0
(-7682 1825);
DISPLAY 0.638298 (-7682 1825);
PAINT MONO (-7682 1825);
FORCEPROP 1 LAST COMMENT_BODY TRUE
J 0
(-7275 1725);
DISPLAY 1.170213 (-7275 1725);
PAINT GREEN (-7275 1725);
DISPLAY INVISIBLE (-7275 1725);
FORCEPROP 1 LAST OFFPAGE TRUE
J 0
(-7075 1700);
DISPLAY 1.170213 (-7075 1700);
PAINT GREEN (-7075 1700);
DISPLAY INVISIBLE (-7075 1700);
FORCEPROP 2 LAST ROOM PVCCIN_CPU0_VR
J 0
(-7950 1900);
DISPLAY 1.361702 (-7950 1900);
PAINT ORANGE (-7950 1900);
DISPLAY INVISIBLE (-7950 1900);
FORCEPROP 2 LAST CDS_LIB mstr_standard
J 0
(-7400 1825);
PAINT ORANGE (-7400 1825);
DISPLAY INVISIBLE (-7400 1825);
FORCEPROP 2 LAST PATH I92
J 0
(-7350 1900);
DISPLAY 1.021277 (-7350 1900);
PAINT ORANGE (-7350 1900);
DISPLAY INVISIBLE (-7350 1900);
FORCEADD OFFPAGE..1
(-7400 1575);
FORCEPROP 2 LAST $XR0 205 
J 0
(-7682 1575);
DISPLAY 0.638298 (-7682 1575);
PAINT MONO (-7682 1575);
FORCEPROP 1 LAST COMMENT_BODY TRUE
J 0
(-7275 1475);
DISPLAY 1.170213 (-7275 1475);
PAINT GREEN (-7275 1475);
DISPLAY INVISIBLE (-7275 1475);
FORCEPROP 1 LAST OFFPAGE TRUE
J 0
(-7075 1450);
DISPLAY 1.170213 (-7075 1450);
PAINT GREEN (-7075 1450);
DISPLAY INVISIBLE (-7075 1450);
FORCEPROP 2 LAST ROOM PVCCIN_CPU0_VR
J 0
(-7950 1650);
DISPLAY 1.361702 (-7950 1650);
PAINT ORANGE (-7950 1650);
DISPLAY INVISIBLE (-7950 1650);
FORCEPROP 2 LAST CDS_LIB mstr_standard
J 0
(-7400 1575);
PAINT ORANGE (-7400 1575);
DISPLAY INVISIBLE (-7400 1575);
FORCEPROP 2 LAST PATH I93
J 0
(-7350 1650);
DISPLAY 1.021277 (-7350 1650);
PAINT ORANGE (-7350 1650);
DISPLAY INVISIBLE (-7350 1650);
FORCEADD OFFPAGE..1
(-7400 1725);
FORCEPROP 2 LAST $XR0 201 
J 0
(-7682 1725);
DISPLAY 0.638298 (-7682 1725);
PAINT MONO (-7682 1725);
FORCEPROP 1 LAST COMMENT_BODY TRUE
J 0
(-7275 1625);
DISPLAY 1.170213 (-7275 1625);
PAINT GREEN (-7275 1625);
DISPLAY INVISIBLE (-7275 1625);
FORCEPROP 1 LAST OFFPAGE TRUE
J 0
(-7075 1600);
DISPLAY 1.170213 (-7075 1600);
PAINT GREEN (-7075 1600);
DISPLAY INVISIBLE (-7075 1600);
FORCEPROP 2 LAST ROOM PVCCIN_CPU0_VR
J 0
(-7950 1800);
DISPLAY 1.361702 (-7950 1800);
PAINT ORANGE (-7950 1800);
DISPLAY INVISIBLE (-7950 1800);
FORCEPROP 2 LAST CDS_LIB mstr_standard
J 0
(-7400 1725);
PAINT ORANGE (-7400 1725);
DISPLAY INVISIBLE (-7400 1725);
FORCEPROP 2 LAST PATH I94
J 0
(-7350 1800);
DISPLAY 1.021277 (-7350 1800);
PAINT ORANGE (-7350 1800);
DISPLAY INVISIBLE (-7350 1800);
FORCEADD OFFPAGE..1
(-7400 1675);
FORCEPROP 2 LAST $XR0 204 
J 0
(-7682 1675);
DISPLAY 0.638298 (-7682 1675);
PAINT MONO (-7682 1675);
FORCEPROP 1 LAST COMMENT_BODY TRUE
J 0
(-7275 1575);
DISPLAY 1.170213 (-7275 1575);
PAINT GREEN (-7275 1575);
DISPLAY INVISIBLE (-7275 1575);
FORCEPROP 1 LAST OFFPAGE TRUE
J 0
(-7075 1550);
DISPLAY 1.170213 (-7075 1550);
PAINT GREEN (-7075 1550);
DISPLAY INVISIBLE (-7075 1550);
FORCEPROP 2 LAST ROOM PVCCIN_CPU0_VR
J 0
(-7950 1750);
DISPLAY 1.361702 (-7950 1750);
PAINT ORANGE (-7950 1750);
DISPLAY INVISIBLE (-7950 1750);
FORCEPROP 2 LAST CDS_LIB mstr_standard
J 0
(-7400 1675);
PAINT ORANGE (-7400 1675);
DISPLAY INVISIBLE (-7400 1675);
FORCEPROP 2 LAST PATH I95
J 0
(-7350 1750);
DISPLAY 1.021277 (-7350 1750);
PAINT ORANGE (-7350 1750);
DISPLAY INVISIBLE (-7350 1750);
FORCEADD OFFPAGE..1
(-7400 1525);
FORCEPROP 2 LAST $XR0 205 
J 0
(-7682 1525);
DISPLAY 0.638298 (-7682 1525);
PAINT MONO (-7682 1525);
FORCEPROP 1 LAST COMMENT_BODY TRUE
J 0
(-7275 1425);
DISPLAY 1.170213 (-7275 1425);
PAINT GREEN (-7275 1425);
DISPLAY INVISIBLE (-7275 1425);
FORCEPROP 1 LAST OFFPAGE TRUE
J 0
(-7075 1400);
DISPLAY 1.170213 (-7075 1400);
PAINT GREEN (-7075 1400);
DISPLAY INVISIBLE (-7075 1400);
FORCEPROP 2 LAST ROOM PVCCIN_CPU0_VR
J 0
(-7950 1600);
DISPLAY 1.361702 (-7950 1600);
PAINT ORANGE (-7950 1600);
DISPLAY INVISIBLE (-7950 1600);
FORCEPROP 2 LAST CDS_LIB mstr_standard
J 0
(-7400 1525);
PAINT ORANGE (-7400 1525);
DISPLAY INVISIBLE (-7400 1525);
FORCEPROP 2 LAST PATH I96
J 0
(-7350 1600);
DISPLAY 1.021277 (-7350 1600);
PAINT ORANGE (-7350 1600);
DISPLAY INVISIBLE (-7350 1600);
FORCEADD OFFPAGE..1
(-7400 1475);
FORCEPROP 2 LAST $XR0 205 
J 0
(-7682 1475);
DISPLAY 0.638298 (-7682 1475);
PAINT MONO (-7682 1475);
FORCEPROP 1 LAST COMMENT_BODY TRUE
J 0
(-7275 1375);
DISPLAY 1.170213 (-7275 1375);
PAINT GREEN (-7275 1375);
DISPLAY INVISIBLE (-7275 1375);
FORCEPROP 1 LAST OFFPAGE TRUE
J 0
(-7075 1350);
DISPLAY 1.170213 (-7075 1350);
PAINT GREEN (-7075 1350);
DISPLAY INVISIBLE (-7075 1350);
FORCEPROP 2 LAST ROOM PVCCIN_CPU0_VR
J 0
(-7950 1550);
DISPLAY 1.361702 (-7950 1550);
PAINT ORANGE (-7950 1550);
DISPLAY INVISIBLE (-7950 1550);
FORCEPROP 2 LAST CDS_LIB mstr_standard
J 0
(-7400 1475);
PAINT ORANGE (-7400 1475);
DISPLAY INVISIBLE (-7400 1475);
FORCEPROP 2 LAST PATH I97
J 0
(-7350 1550);
DISPLAY 1.021277 (-7350 1550);
PAINT ORANGE (-7350 1550);
DISPLAY INVISIBLE (-7350 1550);
FORCEADD RES..1
(-2400 2725);
FORCEPROP 1 LAST WATTAGE 1/16W
J 2
(-2425 2525);
DISPLAY 0.617021 (-2425 2525);
PAINT SKYBLUE (-2425 2525);
FORCEPROP 1 LAST VALUE 0.0
J 2
(-2525 2575);
DISPLAY 0.617021 (-2525 2575);
PAINT SKYBLUE (-2525 2575);
FORCEPROP 1 LAST MATERIAL CHIP
J 0
(-2375 2525);
DISPLAY 0.617021 (-2375 2525);
PAINT SKYBLUE (-2375 2525);
FORCEPROP 1 LASTPIN (-2500 2725) $PN 1
J 0
(-2488 2737);
DISPLAY 0.617021 (-2488 2737);
PAINT ORANGE (-2488 2737);
FORCEPROP 1 LAST LOCATION R4D66
J 0
(-2450 2775);
DISPLAY 0.617021 (-2450 2775);
PAINT AQUA (-2450 2775);
FORCEPROP 1 LAST TOLERANCE 5%
J 0
(-2475 2575);
DISPLAY 0.617021 (-2475 2575);
PAINT SKYBLUE (-2475 2575);
FORCEPROP 1 LASTPIN (-2300 2725) $PN 2
J 0
(-2338 2737);
DISPLAY 0.617021 (-2338 2737);
PAINT ORANGE (-2338 2737);
FORCEPROP 1 LAST PACK_TYPE 0402
J 0
(-2375 2575);
DISPLAY 0.617021 (-2375 2575);
PAINT SKYBLUE (-2375 2575);
FORCEPROP 1 LAST PART_NUMBER G21497-005
J 0
(-2550 2625);
DISPLAY 0.617021 (-2550 2625);
PAINT BLUE (-2550 2625);
FORCEPROP 2 LAST CDS_LOCATION R4D66
J 0
(-2450 2775);
DISPLAY 0.617021 (-2450 2775);
PAINT AQUA (-2450 2775);
DISPLAY INVISIBLE (-2450 2775);
FORCEPROP 2 LAST CDS_LIB mstr_discrete
J 0
(-2400 2725);
PAINT ORANGE (-2400 2725);
DISPLAY INVISIBLE (-2400 2725);
FORCEPROP 2 LAST SEC_TYPE 0402
J 0
(-2450 2925);
DISPLAY 1.021277 (-2450 2925);
PAINT ORANGE (-2450 2925);
DISPLAY INVISIBLE (-2450 2925);
FORCEPROP 2 LAST SEC 1
J 0
(-2450 2925);
DISPLAY 0.680851 (-2450 2925);
PAINT MONO (-2450 2925);
DISPLAY INVISIBLE (-2450 2925);
FORCEPROP 1 LAST PATH I98
J 0
(-2450 2875);
DISPLAY 0.978723 (-2450 2875);
PAINT WHITE (-2450 2875);
DISPLAY INVISIBLE (-2450 2875);
FORCEPROP 2 LAST ROOM PVCCIN_CPU0_VR
J 0
(-2450 2825);
DISPLAY 1.361702 (-2450 2825);
PAINT ORANGE (-2450 2825);
DISPLAY INVISIBLE (-2450 2825);
FORCEADD DNS..2
(-1095 1995);
PAINT RED (-1095 1995);
FORCEPROP 1 LAST COMMENT_BODY TRUE
R 1
J 0
(-1020 1770);
DISPLAY 0.872340 (-1020 1770);
PAINT GREEN (-1020 1770);
DISPLAY INVISIBLE (-1020 1770);
FORCEPROP 2 LAST CDS_LIB mstr_misc
J 0
(-1095 1995);
PAINT ORANGE (-1095 1995);
DISPLAY INVISIBLE (-1095 1995);
FORCEADD DNS..2
(-845 1995);
PAINT RED (-845 1995);
FORCEPROP 1 LAST COMMENT_BODY TRUE
R 1
J 0
(-770 1770);
DISPLAY 0.872340 (-770 1770);
PAINT GREEN (-770 1770);
DISPLAY INVISIBLE (-770 1770);
FORCEPROP 2 LAST CDS_LIB mstr_misc
J 0
(-845 1995);
PAINT ORANGE (-845 1995);
DISPLAY INVISIBLE (-845 1995);
FORCEADD DNS..2
(-1570 4195);
PAINT RED (-1570 4195);
FORCEPROP 1 LAST COMMENT_BODY TRUE
R 1
J 0
(-1495 3970);
DISPLAY 0.872340 (-1495 3970);
PAINT GREEN (-1495 3970);
DISPLAY INVISIBLE (-1495 3970);
FORCEPROP 2 LAST CDS_LIB mstr_misc
J 0
(-1570 4195);
PAINT ORANGE (-1570 4195);
DISPLAY INVISIBLE (-1570 4195);
FORCEADD DESIGN_NOTE..1
(-3125 550);
FORCEPROP 0 LAST L1 REMOVE VR DONGLE HEADER IN MASS PRODUCTION
J 0
(-3325 425);
DISPLAY 0.617021 (-3325 425);
PAINT WHITE (-3325 425);
FORCEPROP 1 LAST COMMENT_BODY TRUE
J 0
(-3100 650);
DISPLAY 1.319149 (-3100 650);
PAINT WHITE (-3100 650);
DISPLAY INVISIBLE (-3100 650);
FORCEPROP 2 LAST CDS_LIB mstr_symbols
J 0
(-3125 550);
PAINT WHITE (-3125 550);
DISPLAY INVISIBLE (-3125 550);
FORCEADD DNS..2
(-2070 3745);
PAINT RED (-2070 3745);
FORCEPROP 1 LAST COMMENT_BODY TRUE
R 1
J 0
(-1995 3520);
DISPLAY 0.872340 (-1995 3520);
PAINT GREEN (-1995 3520);
DISPLAY INVISIBLE (-1995 3520);
FORCEPROP 2 LAST CDS_LIB mstr_misc
J 0
(-2070 3745);
PAINT ORANGE (-2070 3745);
DISPLAY INVISIBLE (-2070 3745);
FORCEADD DESIGN_NOTE..1
(-4100 1425);
FORCEPROP 0 LAST L1 SMBUS ADDRESS: 0X90
J 0
(-4300 1300);
DISPLAY 1.021277 (-4300 1300);
PAINT ORANGE (-4300 1300);
FORCEPROP 1 LAST COMMENT_BODY TRUE
J 0
(-4075 1525);
DISPLAY 0.978723 (-4075 1525);
PAINT ORANGE (-4075 1525);
DISPLAY INVISIBLE (-4075 1525);
FORCEPROP 2 LAST CDS_LIB mstr_symbols
J 0
(-4100 1425);
PAINT ORANGE (-4100 1425);
DISPLAY INVISIBLE (-4100 1425);
FORCEADD INTEL_CORP_BPAGE..1
(-125 0);
FORCEPROP 1 LAST CDS_CON_LAST_MODIFIED Tue Dec 01 11:52:21 2015
J 0
(-1550 325);
PAINT ORANGE (-1550 325);
DISPLAY INVISIBLE (-1550 325);
FORCEPROP 1 LAST CUSTOM_TXT_CDS <CURRENT_DESIGN_SHEET> OF <TOTAL_DESIGN_SHEETS>
J 0
(-625 25);
PAINT GREEN (-625 25);
FORCEPROP 1 LAST CUSTOM_TXT_CDS <CON_LAST_MODIFIED>
J 0
(-2050 350);
PAINT GREEN (-2050 350);
FORCEPROP 2 LAST CUSTOM_TXT_CDS <XR_PAGE_TITLE>
J 0
(-8015 5250);
DISPLAY 0.638298 (-8015 5250);
PAINT PINK (-8015 5250);
DISPLAY INVISIBLE (-8015 5250);
FORCEPROP 1 LAST SCH_TITLE VCCIN CPU0 (1 OF 4)
J 0
(-8075 50);
DISPLAY 1.212766 (-8075 50);
PAINT ORANGE (-8075 50);
FORCEPROP 1 LAST SCH_ADDRESS1 2200 Mission College Blvd.
J 0
(-4100 125);
DISPLAY 0.617021 (-4100 125);
PAINT GREEN (-4100 125);
FORCEPROP 1 LAST SCH_ADDRESS2 P.O. BOX 58119
J 0
(-4100 75);
DISPLAY 0.617021 (-4100 75);
PAINT GREEN (-4100 75);
FORCEPROP 1 LAST SCH_ADDRESS3 Santa Clara, CA 95052-8119
J 0
(-4100 25);
DISPLAY 0.617021 (-4100 25);
PAINT GREEN (-4100 25);
FORCEPROP 1 LAST SCH_NUMBER H4694802
J 0
(-1425 150);
DISPLAY 1.212766 (-1425 150);
PAINT YELLOW (-1425 150);
FORCEPROP 1 LAST SCH_DEPT BESD
J 1
(-4575 100);
DISPLAY 1.212766 (-4575 100);
PAINT YELLOW (-4575 100);
FORCEPROP 1 LAST SCH_REV 2.420
J 0
(-375 150);
DISPLAY 0.978723 (-375 150);
PAINT YELLOW (-375 150);
FORCEPROP 1 LAST COMMENT_BODY TRUE
J 0
(-113 12);
DISPLAY 0.468085 (-113 12);
PAINT GREEN (-113 12);
DISPLAY INVISIBLE (-113 12);
FORCEPROP 2 LAST CDS_LIB mstr_symbols
J 0
(-125 0);
PAINT MONO (-125 0);
DISPLAY INVISIBLE (-125 0);
FORCEPROP 2 LAST PAGE_BORDER TRUE
J 0
(-8015 5250);
DISPLAY 0.638298 (-8015 5250);
PAINT PINK (-8015 5250);
DISPLAY INVISIBLE (-8015 5250);
FORCEPROP 2 LAST CDS_XR_PAGE_TITLE CR-201 : @BASEBOARD_FAB2_LIB.BASEBOARD_FAB2(SCH_1):PAGE201
J 0
(-8015 5250);
DISPLAY 0.638298 (-8015 5250);
PAINT PINK (-8015 5250);
DISPLAY INVISIBLE (-8015 5250);
FORCEADD DESIGN_NOTE..1
(-1000 4900);
PAINT PURPLE (-1000 4900);
FORCEPROP 0 LAST L1 SVID ADDRESS 0X0 / 0X1
J 0
(-1200 4775);
PAINT VIOLET (-1200 4775);
FORCEPROP 1 LAST COMMENT_BODY TRUE
J 0
(-975 5000);
DISPLAY 1.319149 (-975 5000);
PAINT GREEN (-975 5000);
DISPLAY INVISIBLE (-975 5000);
FORCEPROP 2 LAST ROOM PVCCIN_CPU0_VR
J 0
(-1200 4850);
PAINT MONO (-1200 4850);
DISPLAY INVISIBLE (-1200 4850);
FORCEPROP 2 LAST BOM_COST SM_CONTROLLER
J 0
(-1200 4850);
PAINT MONO (-1200 4850);
DISPLAY INVISIBLE (-1200 4850);
FORCEPROP 2 LAST CDS_LIB mstr_symbols
J 0
(-1000 4900);
PAINT MONO (-1000 4900);
DISPLAY INVISIBLE (-1000 4900);
WIRE 16 -1 (-4250 4550)(-4250 4375);
WIRE 16 -1 (-1575 4300)(-1575 4375);
WIRE 16 -1 (-1575 4375)(-1925 4375);
WIRE 16 -1 (-1925 4200)(-1925 4375);
WIRE 16 -1 (-2075 4375)(-1925 4375);
WIRE 16 -1 (-2075 3850)(-2075 4375);
WIRE 16 -1 (-2500 4375)(-2075 4375);
WIRE 16 -1 (-2500 4025)(-2500 4375);
WIRE 16 -1 (-2775 4375)(-2500 4375);
WIRE 16 -1 (-2775 4025)(-2775 4375);
WIRE 16 -1 (-3050 4375)(-2775 4375);
WIRE 16 -1 (-3050 4225)(-3050 4375);
WIRE 16 -1 (-3050 4375)(-3050 4500);
WIRE 16 -1 (-850 2175)(-1100 2175);
WIRE 16 -1 (-850 2100)(-850 2175);
WIRE 16 -1 (-850 2175)(-375 2175);
WIRE 16 -1 (-1100 2175)(-1100 2100);
WIRE 16 -1 (-375 2275)(-375 2175);
WIRE 16 -1 (-3050 825)(-2900 825);
WIRE 16 -1 (-1450 1975)(-1450 1900);
WIRE 16 -1 (-1275 3850)(-1275 3900);
WIRE 16 -1 (-1475 725)(-1475 900);
WIRE 16 -1 (-1875 850)(-1875 900);
WIRE 16 -1 (-3350 1825)(-3075 1825);
WIRE 16 -1 (-3075 1600)(-3075 1825);
WIRE 16 -1 (-3550 3775)(-3550 3825);
WIRE 16 -1 (-3950 3775)(-3950 3825);
WIRE 16 -1 (-4400 625)(-4400 825);
WIRE 16 -1 (-4725 625)(-4725 800);
WIRE 16 -1 (-4775 4450)(-4775 4475);
WIRE 16 -1 (-4775 4475)(-5325 4475);
WIRE 16 -1 (-5325 4475)(-5650 4475);
WIRE 16 -1 (-5325 4475)(-5325 4775);
WIRE 16 -1 (-5650 4375)(-5650 4475);
WIRE 16 -1 (-6050 4775)(-6050 4725);
WIRE 16 -1 (-6050 4025)(-6050 4100);
WIRE 16 -1 (-6300 4050)(-6300 4125);
WIRE 16 -1 (-5450 1075)(-5450 1175);
WIRE 16 -1 (-5125 825)(-5125 900);
WIRE 16 -1 (-6475 1350)(-7625 1350);
FORCEPROP 2 LAST SIG_NAME VR_PVCCIN_CPU0_VD12
J 0
(-7590 1365);
DISPLAY 0.617021 (-7590 1365);
PAINT ORANGE (-7590 1365);
WIRE 16 -1 (-7350 2075)(-6350 2075);
FORCEPROP 2 LAST SIG_NAME VSENSE_PVSA_CPU0_P
J 0
(-7365 2090);
DISPLAY 0.617021 (-7365 2090);
PAINT ORANGE (-7365 2090);
WIRE 16 -1 (-7325 2525)(-6775 2525);
FORCEPROP 2 LAST SIG_NAME VSENSE_PVCCIN_CPU0_P
J 0
(-7340 2540);
DISPLAY 0.617021 (-7340 2540);
PAINT ORANGE (-7340 2540);
WIRE 16 -1 (-7350 2675)(-4250 2675);
FORCEPROP 2 LAST SIG_NAME ISENSE_PVCCIN_CPU0_PH5_IMON
J 0
(-7340 2690);
DISPLAY 0.617021 (-7340 2690);
PAINT ORANGE (-7340 2690);
WIRE 16 -1 (-7350 2775)(-4250 2775);
FORCEPROP 2 LAST SIG_NAME ISENSE_PVCCIN_CPU0_PH3_IMON
J 0
(-7340 2790);
DISPLAY 0.617021 (-7340 2790);
PAINT ORANGE (-7340 2790);
WIRE 16 -1 (-7350 2825)(-4250 2825);
FORCEPROP 2 LAST SIG_NAME ISENSE_PVCCIN_CPU0_PH2_IMON
J 0
(-7340 2840);
DISPLAY 0.617021 (-7340 2840);
PAINT ORANGE (-7340 2840);
WIRE 16 -1 (-7350 2875)(-4250 2875);
FORCEPROP 2 LAST SIG_NAME ISENSE_PVCCIN_CPU0_PH1_IMON
J 0
(-7340 2890);
DISPLAY 0.617021 (-7340 2890);
PAINT ORANGE (-7340 2890);
WIRE 16 -1 (-6475 3525)(-6475 3125);
WIRE 16 -1 (-4250 3125)(-6475 3125);
WIRE 16 -1 (-7350 3125)(-6475 3125);
FORCEPROP 2 LAST SIG_NAME VR_PVCCIN_CPU0_AIREF2
J 0
(-7315 3140);
DISPLAY 0.617021 (-7315 3140);
PAINT ORANGE (-7315 3140);
WIRE 16 -1 (-6850 3525)(-6850 3175);
WIRE 16 -1 (-4250 3175)(-6850 3175);
WIRE 16 -1 (-7350 3175)(-6850 3175);
FORCEPROP 2 LAST SIG_NAME VR_PVCCIN_CPU0_AIREF1
J 0
(-7315 3190);
DISPLAY 0.617021 (-7315 3190);
PAINT ORANGE (-7315 3190);
WIRE 16 -1 (-6450 2475)(-6450 2525);
WIRE 16 -1 (-4250 2525)(-6450 2525);
FORCEPROP 2 LAST SIG_NAME VSENSE_PVCCIN_CPU0_AVSP
J 0
(-5640 2540);
DISPLAY 0.617021 (-5640 2540);
PAINT ORANGE (-5640 2540);
FORCEPROP 2 LASTPROP $XRERR UNIQUE?
J 0
(-5880 2540);
DISPLAY 0.638298 (-5880 2540);
PAINT MONO (-5880 2540);
DISPLAY INVISIBLE (-5880 2540);
WIRE 16 -1 (-6575 2525)(-6450 2525);
WIRE 16 -1 (-5125 1925)(-4250 1925);
WIRE 16 -1 (-5125 1575)(-5125 1925);
WIRE 16 -1 (-5125 1100)(-5125 1575);
WIRE 16 -1 (-7350 1575)(-5125 1575);
FORCEPROP 2 LAST SIG_NAME A_TSENSE_PVSA_CPU0
J 0
(-7340 1590);
DISPLAY 0.617021 (-7340 1590);
PAINT ORANGE (-7340 1590);
WIRE 16 -1 (-4250 2025)(-4925 2025);
FORCEPROP 0 LAST SIG_NAME TP_PVCCIN_CPU0_RESET
J 0
(-4910 2035);
DISPLAY 0.617021 (-4910 2035);
PAINT ORANGE (-4910 2035);
FORCEPROP 2 LASTPROP $XRERR UNIQUE?
J 0
(-5165 2025);
DISPLAY 0.638298 (-5165 2025);
PAINT MONO (-5165 2025);
DISPLAY INVISIBLE (-5165 2025);
WIRE 16 -1 (-4725 1775)(-4250 1775);
FORCEPROP 0 LAST VOLTAGE 3.3
J 0
(-4475 1825);
DISPLAY 1.021277 (-4475 1825);
PAINT SKYBLUE (-4475 1825);
DISPLAY INVISIBLE (-4475 1825);
WIRE 16 -1 (-4725 1000)(-4725 1775);
FORCEPROP 0 LAST SIG_NAME VR_PVCCIN_CPU0_XADDR1
R 1
J 0
(-4735 1060);
DISPLAY 0.617021 (-4735 1060);
PAINT ORANGE (-4735 1060);
FORCEPROP 2 LASTPROP $XRERR UNIQUE?
J 0
(-4975 1060);
DISPLAY 0.638298 (-4975 1060);
PAINT MONO (-4975 1060);
DISPLAY INVISIBLE (-4975 1060);
WIRE 16 -1 (-4250 1825)(-5025 1825);
WIRE 16 -1 (-5025 1825)(-5025 1475);
WIRE 16 -1 (-7350 1475)(-5025 1475);
FORCEPROP 2 LAST SIG_NAME ISENSE_PVSA_CPU0_IMON
J 0
(-7340 1490);
DISPLAY 0.617021 (-7340 1490);
PAINT ORANGE (-7340 1490);
WIRE 16 -1 (-4250 1875)(-5075 1875);
WIRE 16 -1 (-5075 1875)(-5075 1525);
WIRE 16 -1 (-5075 1525)(-6000 1525);
WIRE 16 -1 (-6000 1350)(-6000 1525);
WIRE 16 -1 (-6000 1525)(-7350 1525);
FORCEPROP 2 LAST SIG_NAME VR_PVSA_CPU0_BIREF1
J 0
(-7327 1541);
DISPLAY 0.617021 (-7327 1541);
PAINT ORANGE (-7327 1541);
WIRE 16 -1 (-6275 1350)(-6000 1350);
WIRE 16 -1 (-4400 1725)(-4250 1725);
WIRE 16 -1 (-4400 1025)(-4400 1725);
FORCEPROP 0 LAST VOLTAGE 3.3
J 0
(-4400 1150);
DISPLAY 1.021277 (-4400 1150);
PAINT SKYBLUE (-4400 1150);
DISPLAY INVISIBLE (-4400 1150);
FORCEPROP 0 LAST SIG_NAME VR_PVCCIN_CPU0_XADDR2
R 1
J 0
(-4410 1085);
DISPLAY 0.617021 (-4410 1085);
PAINT ORANGE (-4410 1085);
FORCEPROP 2 LASTPROP $XRERR UNIQUE?
J 0
(-4650 1085);
DISPLAY 0.638298 (-4650 1085);
PAINT MONO (-4650 1085);
DISPLAY INVISIBLE (-4650 1085);
WIRE 16 -1 (-5200 2225)(-5300 2225);
WIRE 16 -1 (-5300 1825)(-5300 2225);
WIRE 16 -1 (-7350 1825)(-5300 1825);
FORCEPROP 2 LAST SIG_NAME FM_PVCCIN_PVCCSA_CPU0_EN_LVC1
J 0
(-7343 1826);
DISPLAY 0.617021 (-7343 1826);
PAINT ORANGE (-7343 1826);
WIRE 16 -1 (-5175 3825)(-5175 3725);
WIRE 16 -1 (-5575 3825)(-5175 3825);
WIRE 16 -1 (-5575 3825)(-5575 3725);
WIRE 16 -1 (-6000 3825)(-5575 3825);
WIRE 16 -1 (-6000 3825)(-6000 3725);
WIRE 16 -1 (-6000 3825)(-6475 3825);
WIRE 16 -1 (-6475 3825)(-6475 3725);
WIRE 16 -1 (-6850 3825)(-6475 3825);
WIRE 16 -1 (-6850 3725)(-6850 3825);
WIRE 16 -1 (-7350 3825)(-6850 3825);
FORCEPROP 2 LAST SIG_NAME VR_PVCCIN_CPU0_VD12
J 0
(-7315 3840);
DISPLAY 0.617021 (-7315 3840);
PAINT ORANGE (-7315 3840);
WIRE 16 -1 (-4250 2975)(-5175 2975);
WIRE 16 -1 (-5175 2975)(-5175 3525);
WIRE 16 -1 (-7350 2975)(-5175 2975);
FORCEPROP 2 LAST SIG_NAME VR_PVCCIN_CPU0_AIREF5
J 0
(-7315 2990);
DISPLAY 0.617021 (-7315 2990);
PAINT ORANGE (-7315 2990);
WIRE 16 -1 (-5575 3525)(-5575 3025);
WIRE 16 -1 (-4250 3025)(-5575 3025);
WIRE 16 -1 (-7350 3025)(-5575 3025);
FORCEPROP 2 LAST SIG_NAME VR_PVCCIN_CPU0_AIREF4
J 0
(-7315 3040);
DISPLAY 0.617021 (-7315 3040);
PAINT ORANGE (-7315 3040);
WIRE 16 -1 (-6000 3525)(-6000 3075);
WIRE 16 -1 (-4250 3075)(-6000 3075);
WIRE 16 -1 (-7350 3075)(-6000 3075);
FORCEPROP 2 LAST SIG_NAME VR_PVCCIN_CPU0_AIREF3
J 0
(-7315 3090);
DISPLAY 0.617021 (-7315 3090);
PAINT ORANGE (-7315 3090);
WIRE 16 -1 (-5550 2425)(-4250 2425);
WIRE 16 -1 (-5550 2275)(-5550 2425);
FORCEPROP 2 LAST SIG_NAME VSENSE_PVSA_CPU0_BVSP
J 0
(-5590 2440);
DISPLAY 0.617021 (-5590 2440);
PAINT ORANGE (-5590 2440);
FORCEPROP 2 LASTPROP $XRERR UNIQUE?
J 0
(-5830 2440);
DISPLAY 0.638298 (-5830 2440);
PAINT MONO (-5830 2440);
DISPLAY INVISIBLE (-5830 2440);
WIRE 16 -1 (-5550 2175)(-5550 2275);
WIRE 16 -1 (-5975 2275)(-5550 2275);
WIRE 16 -1 (-5975 2075)(-5975 2275);
WIRE 16 -1 (-6150 2075)(-5975 2075);
WIRE 16 -1 (-5250 2175)(-4250 2175);
WIRE 16 -1 (-5250 1725)(-5250 2175);
WIRE 16 -1 (-7350 1725)(-5250 1725);
FORCEPROP 0 LAST VOLTAGE 0.8
J 0
(-7325 1800);
DISPLAY 1.021277 (-7325 1800);
PAINT SKYBLUE (-7325 1800);
DISPLAY INVISIBLE (-7325 1800);
FORCEPROP 2 LAST SIG_NAME VR_PVCCIN_CPU0_AVINSEN
J 0
(-7340 1740);
DISPLAY 0.617021 (-7340 1740);
PAINT ORANGE (-7340 1740);
WIRE 16 -1 (-5200 2125)(-4250 2125);
WIRE 16 -1 (-5200 1675)(-5200 2125);
WIRE 16 -1 (-7350 1675)(-5200 1675);
FORCEPROP 0 LAST VOLTAGE +3.3V
J 0
(-7325 1750);
DISPLAY 1.021277 (-7325 1750);
PAINT SKYBLUE (-7325 1750);
DISPLAY INVISIBLE (-7325 1750);
FORCEPROP 2 LAST SIG_NAME PVCCIN_PVSA_CPU0_IINSEN
J 0
(-7330 1680);
DISPLAY 0.617021 (-7330 1680);
PAINT ORANGE (-7330 1680);
WIRE 16 -1 (-5375 2275)(-4250 2275);
WIRE 16 -1 (-5375 1875)(-5375 2275);
WIRE 16 -1 (-5450 1875)(-5375 1875);
WIRE 16 -1 (-5450 1375)(-5450 1875);
WIRE 16 -1 (-7350 1875)(-5450 1875);
FORCEPROP 2 LAST SIG_NAME A_TSENSE_PVCCIN_CPU0
J 0
(-7365 1890);
DISPLAY 0.617021 (-7365 1890);
PAINT ORANGE (-7365 1890);
WIRE 16 -1 (-4250 2375)(-5450 2375);
WIRE 16 -1 (-5450 2375)(-5450 1925);
WIRE 16 -1 (-5450 1925)(-5550 1925);
WIRE 16 -1 (-5550 1975)(-5550 1925);
WIRE 16 -1 (-5550 1925)(-7350 1925);
FORCEPROP 2 LAST SIG_NAME VSENSE_PVSA_CPU0_N
J 0
(-7365 1940);
DISPLAY 0.617021 (-7365 1940);
PAINT ORANGE (-7365 1940);
WIRE 16 -1 (-4250 2475)(-6050 2475);
WIRE 16 -1 (-6050 2475)(-6050 2250);
WIRE 16 -1 (-6050 2250)(-6450 2250);
WIRE 16 -1 (-6450 2275)(-6450 2250);
WIRE 16 -1 (-6450 2250)(-7350 2250);
FORCEPROP 2 LAST SIG_NAME VSENSE_PVCCIN_CPU0_N
J 0
(-7365 2265);
DISPLAY 0.617021 (-7365 2265);
PAINT ORANGE (-7365 2265);
WIRE 16 -1 (-4775 2625)(-4250 2625);
FORCEPROP 0 LAST SIG_NAME TP_PVCCIN_CPU0_AISEN6
J 0
(-4760 2635);
DISPLAY 0.617021 (-4760 2635);
PAINT ORANGE (-4760 2635);
FORCEPROP 2 LASTPROP $XRERR UNIQUE?
J 0
(-5015 2625);
DISPLAY 0.638298 (-5015 2625);
PAINT MONO (-5015 2625);
DISPLAY INVISIBLE (-5015 2625);
WIRE 16 -1 (-4250 2925)(-4700 2925);
FORCEPROP 0 LAST SIG_NAME TP_PVCCIN_CPU0_AIREF6
J 0
(-4710 2935);
DISPLAY 0.617021 (-4710 2935);
PAINT ORANGE (-4710 2935);
FORCEPROP 2 LASTPROP $XRERR UNIQUE?
J 0
(-4940 2925);
DISPLAY 0.638298 (-4940 2925);
PAINT MONO (-4940 2925);
DISPLAY INVISIBLE (-4940 2925);
WIRE 16 -1 (-4450 3950)(-4450 3275);
WIRE 16 -1 (-5300 3950)(-4450 3950);
FORCEPROP 2 LAST SIG_NAME SVID_VCLK_PVCCIN_CPU0
J 0
(-5190 3965);
DISPLAY 0.617021 (-5190 3965);
PAINT ORANGE (-5190 3965);
FORCEPROP 2 LASTPROP $XRERR UNIQUE?
J 0
(-5430 3965);
DISPLAY 0.638298 (-5430 3965);
PAINT MONO (-5430 3965);
DISPLAY INVISIBLE (-5430 3965);
WIRE 16 -1 (-4450 3275)(-4250 3275);
WIRE 16 -1 (-5500 3950)(-5650 3950);
WIRE 16 -1 (-5650 4175)(-5650 3950);
WIRE 16 -1 (-7350 3950)(-5650 3950);
FORCEPROP 2 LAST SIG_NAME SVID_CLK0_CPU0_R
J 0
(-7350 3960);
DISPLAY 0.617021 (-7350 3960);
PAINT ORANGE (-7350 3960);
WIRE 16 -1 (-4775 2925)(-4775 4250);
FORCEPROP 0 LAST VOLTAGE 3.3
J 0
(-4775 3650);
DISPLAY 1.021277 (-4775 3650);
PAINT SKYBLUE (-4775 3650);
DISPLAY INVISIBLE (-4775 3650);
WIRE 16 -1 (-4775 2925)(-4950 2925);
WIRE 16 -1 (-4950 2925)(-4950 2225);
FORCEPROP 2 LAST SIG_NAME VR_PVCCIN_CPU0_VREN
J 0
(-4915 2240);
DISPLAY 0.617021 (-4915 2240);
PAINT ORANGE (-4915 2240);
FORCEPROP 2 LASTPROP $XRERR UNIQUE?
J 0
(-5155 2240);
DISPLAY 0.638298 (-5155 2240);
PAINT MONO (-5155 2240);
DISPLAY INVISIBLE (-5155 2240);
WIRE 16 -1 (-4250 2225)(-4950 2225);
WIRE 16 -1 (-4950 2225)(-5000 2225);
WIRE 16 -1 (-6050 4300)(-6050 4425);
WIRE 16 -1 (-6050 4425)(-6050 4525);
WIRE 16 -1 (-6300 4425)(-6050 4425);
WIRE 16 -1 (-6300 4325)(-6300 4425);
WIRE 16 -1 (-6300 4425)(-7325 4425);
FORCEPROP 0 LAST VOLTAGE 0.8
J 0
(-7325 4500);
DISPLAY 1.021277 (-7325 4500);
PAINT SKYBLUE (-7325 4500);
DISPLAY INVISIBLE (-7325 4500);
FORCEPROP 2 LAST SIG_NAME VR_PVCCIN_CPU0_AVINSEN
J 0
(-7340 4440);
DISPLAY 0.617021 (-7340 4440);
PAINT ORANGE (-7340 4440);
WIRE 16 -1 (-3550 4025)(-3550 4075);
WIRE 16 -1 (-3550 4075)(-3950 4075);
FORCEPROP 2 LAST SIG_NAME VR_PVCCIN_CPU0_VDD
J 0
(-4015 4090);
DISPLAY 0.617021 (-4015 4090);
PAINT ORANGE (-4015 4090);
FORCEPROP 2 LASTPROP $XRERR UNIQUE?
J 0
(-4255 4090);
DISPLAY 0.638298 (-4255 4090);
PAINT MONO (-4255 4090);
DISPLAY INVISIBLE (-4255 4090);
WIRE 16 -1 (-3950 4025)(-3950 4075);
WIRE 16 -1 (-3950 4075)(-4250 4075);
FORCEPROP 0 LAST VOLTAGE 3.3
J 0
(-4100 4125);
DISPLAY 1.021277 (-4100 4125);
PAINT SKYBLUE (-4100 4125);
DISPLAY INVISIBLE (-4100 4125);
WIRE 16 -1 (-4250 4175)(-4250 4075);
WIRE 16 -1 (-4250 4075)(-4250 3375);
WIRE 16 -1 (-2500 2725)(-3350 2725);
FORCEPROP 0 LAST SIG_NAME SVID_VDIO_PVCCIN_CPU0
J 0
(-3235 2735);
DISPLAY 0.617021 (-3235 2735);
PAINT ORANGE (-3235 2735);
FORCEPROP 2 LASTPROP $XRERR UNIQUE?
J 0
(-3475 2735);
DISPLAY 0.638298 (-3475 2735);
PAINT MONO (-3475 2735);
DISPLAY INVISIBLE (-3475 2735);
WIRE 16 -1 (-3350 2225)(-2650 2225);
FORCEPROP 0 LAST SIG_NAME TP_PVCCIN_CPU0_APWM6
J 0
(-3260 2235);
DISPLAY 0.617021 (-3260 2235);
PAINT ORANGE (-3260 2235);
FORCEPROP 2 LASTPROP $XRERR UNIQUE?
J 0
(-2620 2225);
DISPLAY 0.638298 (-2620 2225);
PAINT MONO (-2620 2225);
DISPLAY INVISIBLE (-2620 2225);
WIRE 16 -1 (-3350 3075)(-2600 3075);
FORCEPROP 2 LAST SIG_NAME TP_PVCCIN_CPU0_FAULT1_20
J 0
(-3240 3090);
DISPLAY 0.617021 (-3240 3090);
PAINT ORANGE (-3240 3090);
FORCEPROP 2 LASTPROP $XRERR UNIQUE?
J 0
(-2570 3075);
DISPLAY 0.638298 (-2570 3075);
PAINT MONO (-2570 3075);
DISPLAY INVISIBLE (-2570 3075);
WIRE 16 -1 (-2125 2875)(-3350 2875);
FORCEPROP 2 LAST SIG_NAME SVID_VALERT_VCCIN_CPU0
J 0
(-3240 2890);
DISPLAY 0.617021 (-3240 2890);
PAINT ORANGE (-3240 2890);
FORCEPROP 2 LASTPROP $XRERR UNIQUE?
J 0
(-3480 2890);
DISPLAY 0.638298 (-3480 2890);
PAINT MONO (-3480 2890);
DISPLAY INVISIBLE (-3480 2890);
WIRE 16 -1 (-3350 2625)(-2600 2625);
FORCEPROP 0 LAST SIG_NAME TP_PVCCIN_CPU0_GP1
J 0
(-3235 2635);
DISPLAY 0.617021 (-3235 2635);
PAINT ORANGE (-3235 2635);
FORCEPROP 2 LASTPROP $XRERR UNIQUE?
J 0
(-2570 2625);
DISPLAY 0.638298 (-2570 2625);
PAINT MONO (-2570 2625);
DISPLAY INVISIBLE (-2570 2625);
WIRE 16 -1 (-2500 2975)(-3050 2975);
FORCEPROP 2 LAST SIG_NAME IRQ_PVCCIN_CPU0_VRHOT_LVC3_R_N
J 0
(-3240 2990);
DISPLAY 0.617021 (-3240 2990);
PAINT ORANGE (-3240 2990);
FORCEPROP 2 LASTPROP $XRERR UNIQUE?
J 0
(-3480 2990);
DISPLAY 0.638298 (-3480 2990);
PAINT MONO (-3480 2990);
DISPLAY INVISIBLE (-3480 2990);
WIRE 16 -1 (-3050 4025)(-3050 2975);
WIRE 16 -1 (-3350 2975)(-3050 2975);
WIRE 16 -1 (-2075 3650)(-2075 3125);
WIRE 16 -1 (-3350 3125)(-2075 3125);
FORCEPROP 2 LAST SIG_NAME PU_VR_PVCCIN_CPU0_IMON
J 0
(-3240 3140);
DISPLAY 0.617021 (-3240 3140);
PAINT ORANGE (-3240 3140);
FORCEPROP 2 LASTPROP $XRERR UNIQUE?
J 0
(-3480 3140);
DISPLAY 0.638298 (-3480 3140);
PAINT MONO (-3480 3140);
DISPLAY INVISIBLE (-3480 3140);
WIRE 16 -1 (-3350 2475)(-1100 2475);
FORCEPROP 0 LAST VOLTAGE 3.6
J 0
(-1775 2550);
DISPLAY 1.021277 (-1775 2550);
PAINT SKYBLUE (-1775 2550);
DISPLAY INVISIBLE (-1775 2550);
FORCEPROP 2 LAST SIG_NAME VR_PVCCIN_CPU0_PWM1
J 0
(-1790 2490);
DISPLAY 0.617021 (-1790 2490);
PAINT ORANGE (-1790 2490);
WIRE 16 -1 (-3350 2525)(-1100 2525);
FORCEPROP 2 LAST SIG_NAME VR_PVSA_CPU0_PWM
J 0
(-1790 2540);
DISPLAY 0.617021 (-1790 2540);
PAINT ORANGE (-1790 2540);
WIRE 16 -1 (-3350 2375)(-1100 2375);
FORCEPROP 0 LAST VOLTAGE 3.6
J 0
(-1775 2450);
DISPLAY 1.021277 (-1775 2450);
PAINT SKYBLUE (-1775 2450);
DISPLAY INVISIBLE (-1775 2450);
FORCEPROP 2 LAST SIG_NAME VR_PVCCIN_CPU0_PWM3
J 0
(-1790 2390);
DISPLAY 0.617021 (-1790 2390);
PAINT ORANGE (-1790 2390);
WIRE 16 -1 (-3350 2775)(-1100 2775);
FORCEPROP 2 LAST SIG_NAME VR_PVCCIN_CPU0_VD12
J 0
(-1790 2790);
DISPLAY 0.617021 (-1790 2790);
PAINT ORANGE (-1790 2790);
WIRE 16 -1 (-1100 2975)(-2300 2975);
FORCEPROP 2 LAST SIG_NAME IRQ_PVCCIN_CPU0_VRHOT_LVC3_N
J 0
(-1890 2990);
DISPLAY 0.617021 (-1890 2990);
PAINT ORANGE (-1890 2990);
WIRE 16 -1 (-3350 2275)(-1100 2275);
FORCEPROP 0 LAST VOLTAGE 3.6
J 0
(-1775 2350);
DISPLAY 1.021277 (-1775 2350);
PAINT SKYBLUE (-1775 2350);
DISPLAY INVISIBLE (-1775 2350);
FORCEPROP 2 LAST SIG_NAME VR_PVCCIN_CPU0_PWM5
J 0
(-1790 2290);
DISPLAY 0.617021 (-1790 2290);
PAINT ORANGE (-1790 2290);
WIRE 16 -1 (-3350 2325)(-1100 2325);
FORCEPROP 0 LAST VOLTAGE 3.6
J 0
(-1775 2400);
DISPLAY 1.021277 (-1775 2400);
PAINT SKYBLUE (-1775 2400);
DISPLAY INVISIBLE (-1775 2400);
FORCEPROP 2 LAST SIG_NAME VR_PVCCIN_CPU0_PWM4
J 0
(-1790 2340);
DISPLAY 0.617021 (-1790 2340);
PAINT ORANGE (-1790 2340);
WIRE 16 -1 (-3350 2425)(-1100 2425);
FORCEPROP 0 LAST VOLTAGE 3.6
J 0
(-1775 2500);
DISPLAY 1.021277 (-1775 2500);
PAINT SKYBLUE (-1775 2500);
DISPLAY INVISIBLE (-1775 2500);
FORCEPROP 2 LAST SIG_NAME VR_PVCCIN_CPU0_PWM2
J 0
(-1790 2440);
DISPLAY 0.617021 (-1790 2440);
PAINT ORANGE (-1790 2440);
WIRE 16 -1 (-2775 3825)(-2775 2675);
WIRE 16 -1 (-2775 2675)(-1900 2675);
WIRE 16 -1 (-3350 2675)(-2775 2675);
FORCEPROP 2 LAST SIG_NAME PWRGD_PVSA_CPU0_R
J 0
(-3240 2690);
DISPLAY 0.617021 (-3240 2690);
PAINT ORANGE (-3240 2690);
FORCEPROP 2 LASTPROP $XRERR UNIQUE?
J 0
(-3480 2690);
DISPLAY 0.638298 (-3480 2690);
PAINT MONO (-3480 2690);
DISPLAY INVISIBLE (-3480 2690);
WIRE 16 -1 (-2000 1775)(-2425 1775);
WIRE 16 -1 (-2425 1775)(-2425 2125);
WIRE 16 -1 (-2425 2125)(-3350 2125);
FORCEPROP 2 LAST SIG_NAME SMB_VR_SDA_R
J 0
(-3215 2140);
DISPLAY 0.617021 (-3215 2140);
PAINT ORANGE (-3215 2140);
FORCEPROP 2 LASTPROP $XRERR UNIQUE?
J 0
(-3455 2140);
DISPLAY 0.638298 (-3455 2140);
PAINT MONO (-3455 2140);
DISPLAY INVISIBLE (-3455 2140);
WIRE 16 -1 (-2500 1525)(-2000 1525);
WIRE 16 -1 (-2500 2025)(-2500 1525);
WIRE 16 -1 (-2500 2025)(-3350 2025);
FORCEPROP 2 LAST SIG_NAME SMB_VR_SCL_R
J 0
(-3215 2040);
DISPLAY 0.617021 (-3215 2040);
PAINT ORANGE (-3215 2040);
FORCEPROP 2 LASTPROP $XRERR UNIQUE?
J 0
(-3455 2040);
DISPLAY 0.638298 (-3455 2040);
PAINT MONO (-3455 2040);
DISPLAY INVISIBLE (-3455 2040);
WIRE 16 -1 (-1475 1100)(-1475 1175);
WIRE 16 -1 (-1475 1175)(-1125 1175);
WIRE 16 -1 (-1475 1175)(-1875 1175);
FORCEPROP 2 LAST SIG_NAME VR_PVCCIN_CPU0_VD12
J 0
(-1790 1190);
DISPLAY 0.617021 (-1790 1190);
PAINT ORANGE (-1790 1190);
WIRE 16 -1 (-1875 1100)(-1875 1175);
WIRE 16 -1 (-1100 1900)(-1100 1775);
WIRE 16 -1 (-1100 1775)(-800 1775);
WIRE 16 -1 (-1650 1775)(-1100 1775);
FORCEPROP 2 LAST SIG_NAME SMB_VR_STBY_LVC3_SDA
J 0
(-1465 1790);
DISPLAY 0.617021 (-1465 1790);
PAINT ORANGE (-1465 1790);
WIRE 16 -1 (-1800 1775)(-1650 1775);
WIRE 16 -1 (-1650 1350)(-1650 1775);
WIRE 16 -1 (-2225 1350)(-1650 1350);
WIRE 16 -1 (-2225 875)(-2225 1350);
WIRE 16 -1 (-3050 875)(-2225 875);
WIRE 16 -1 (-850 1900)(-850 1525);
WIRE 16 -1 (-850 1525)(-800 1525);
WIRE 16 -1 (-1575 1525)(-850 1525);
FORCEPROP 2 LAST SIG_NAME SMB_VR_STBY_LVC3_SCL
J 0
(-1465 1540);
DISPLAY 0.617021 (-1465 1540);
PAINT ORANGE (-1465 1540);
WIRE 16 -1 (-1575 1275)(-1575 1525);
WIRE 16 -1 (-1800 1525)(-1575 1525);
WIRE 16 -1 (-2075 1275)(-1575 1275);
WIRE 16 -1 (-2075 725)(-2075 1275);
WIRE 16 -1 (-2975 725)(-2075 725);
WIRE 16 -1 (-2975 775)(-2975 725);
WIRE 16 -1 (-2975 775)(-3050 775);
WIRE 16 -1 (-1700 2675)(-1100 2675);
FORCEPROP 2 LAST SIG_NAME PWRGD_PVSA_CPU0
J 0
(-1715 2690);
DISPLAY 0.617021 (-1715 2690);
PAINT ORANGE (-1715 2690);
WIRE 16 -1 (-1925 2875)(-1100 2875);
FORCEPROP 2 LAST SIG_NAME SVID_ALERT0_CPU0_R_N
J 0
(-1800 2885);
DISPLAY 0.617021 (-1800 2885);
PAINT ORANGE (-1800 2885);
WIRE 16 -1 (-1125 2725)(-1275 2725);
WIRE 16 -1 (-1275 3650)(-1275 2725);
WIRE 16 -1 (-2300 2725)(-1275 2725);
FORCEPROP 0 LAST SIG_NAME SVID_DIO0_CPU0_R
J 0
(-1775 2735);
DISPLAY 0.617021 (-1775 2735);
PAINT ORANGE (-1775 2735);
WIRE 16 -1 (-1100 3075)(-1925 3075);
FORCEPROP 0 LAST SIG_NAME FM_PVCCIN_CPU0_PWR_IN_ALERT_N
J 0
(-1800 3090);
DISPLAY 0.617021 (-1800 3090);
PAINT ORANGE (-1800 3090);
WIRE 16 -1 (-1925 3075)(-1925 3225);
WIRE 16 -1 (-1925 4000)(-1925 3225);
WIRE 16 -1 (-3350 3225)(-1925 3225);
WIRE 16 -1 (-1450 2175)(-1450 3325);
WIRE 16 -1 (-1450 3325)(-1225 3325);
WIRE 16 -1 (-2500 3325)(-1450 3325);
FORCEPROP 0 LAST VOLTAGE 3.3
J 0
(-1975 3375);
DISPLAY 1.021277 (-1975 3375);
PAINT SKYBLUE (-1975 3375);
DISPLAY INVISIBLE (-1975 3375);
WIRE 16 -1 (-2500 3825)(-2500 3325);
WIRE 16 -1 (-3350 3325)(-2500 3325);
FORCEPROP 2 LAST SIG_NAME VR_VRRDY_PVCCIN_CPU0
J 0
(-3240 3340);
DISPLAY 0.617021 (-3240 3340);
PAINT ORANGE (-3240 3340);
FORCEPROP 2 LASTPROP $XRERR UNIQUE?
J 0
(-3480 3340);
DISPLAY 0.638298 (-3480 3340);
PAINT MONO (-3480 3340);
DISPLAY INVISIBLE (-3480 3340);
WIRE 16 -1 (-1025 3325)(-550 3325);
FORCEPROP 2 LAST SIG_NAME PWRGD_PVCCIN_CPU0
J 0
(-1065 3340);
DISPLAY 0.617021 (-1065 3340);
PAINT ORANGE (-1065 3340);
WIRE 16 -1 (-1575 3275)(-1575 4100);
WIRE 16 -1 (-3350 3275)(-1575 3275);
FORCEPROP 2 LAST SIG_NAME PU_VR_PVCCIN_CPU0_FLT1_SMBALT_N_IMON
J 0
(-3240 3290);
DISPLAY 0.617021 (-3240 3290);
PAINT ORANGE (-3240 3290);
FORCEPROP 2 LASTPROP $XRERR UNIQUE?
J 0
(-3480 3290);
DISPLAY 0.638298 (-3480 3290);
PAINT MONO (-3480 3290);
DISPLAY INVISIBLE (-3480 3290);
WIRE 16 -1 (-7350 2725)(-4250 2725);
FORCEPROP 2 LAST SIG_NAME ISENSE_PVCCIN_CPU0_PH4_IMON
J 0
(-7340 2740);
DISPLAY 0.617021 (-7340 2740);
PAINT ORANGE (-7340 2740);
DOT 1 (-6450 2250);
DOT 1 (-6450 2525);
DOT 1 (-6850 3175);
DOT 1 (-6850 3825);
DOT 1 (-6475 3125);
DOT 1 (-6475 3825);
DOT 1 (-6000 1525);
DOT 1 (-5550 1925);
DOT 1 (-5450 1875);
DOT 1 (-5125 1575);
DOT 1 (-5550 2275);
DOT 1 (-5575 3025);
DOT 1 (-5175 2975);
DOT 1 (-6000 3075);
DOT 1 (-6000 3825);
DOT 1 (-5650 3950);
DOT 1 (-5575 3825);
DOT 1 (-4950 2225);
DOT 1 (-4250 4075);
DOT 1 (-6300 4425);
DOT 1 (-6050 4425);
DOT 1 (-5325 4475);
DOT 1 (-3950 4075);
DOT 1 (-3050 2975);
DOT 1 (-2775 2675);
DOT 1 (-2500 3325);
DOT 1 (-1575 1525);
DOT 1 (-1650 1775);
DOT 1 (-1475 1175);
DOT 1 (-1100 1775);
DOT 1 (-850 1525);
DOT 1 (-1275 2725);
DOT 1 (-1925 3225);
DOT 1 (-1450 3325);
DOT 1 (-850 2175);
DOT 1 (-3050 4375);
DOT 1 (-2775 4375);
DOT 1 (-2500 4375);
DOT 1 (-2075 4375);
DOT 1 (-1925 4375);
FORCENOTE
ROOM=PVCCIN_CPU0_VR
(-8030 160) 0;
DISPLAY LEFT (-8030 160);
DISPLAY 1.574468 (-8030 160);
PAINT PURPLE (-8030 160);
FORCENOTE
VR DONGLE HEADER FOR DIGITAL CONTROLLERS
(-3805 1085) 0;
DISPLAY LEFT (-3805 1085);
PAINT PURPLE (-3805 1085);
QUIT
